G04 ================== begin FILE IDENTIFICATION RECORD ==================*
G04 Layout Name:  15669-1.brd*
G04 Film Name:    L2GND*
G04 File Format:  Gerber RS274X*
G04 File Origin:  Cadence Allegro 16.5-S056*
G04 Origin Date:  Wed Nov 16 04:08:38 2016*
G04 *
G04 Layer:  VIA CLASS/L2GND*
G04 Layer:  PIN/L2GND*
G04 Layer:  ETCH/L2GND*
G04 Layer:  DRAWING FORMAT/LAYER_PCB_STORY*
G04 Layer:  DRAWING FORMAT/LAYER_L2GND*
G04 *
G04 Offset:    (0.00 0.00)*
G04 Mirror:    No*
G04 Mode:      Negative*
G04 Rotation:  0*
G04 FullContactRelief:  No*
G04 UndefLineWidth:     6.00*
G04 ================== end FILE IDENTIFICATION RECORD ====================*
%FSLAX35Y35*MOIN*%
%IR0*IPPOS*OFA0.00000B0.00000*MIA0B0*SFA1.00000B1.00000*%
%ADD22O,.115X.072*%
%ADD16C,.03*%
%ADD17C,.032*%
%ADD21C,.036*%
%AMMACRO19*
4,1,15,.00398,.00044,
.003999,.000208,
.004004,-.000025,
.003996,-.000258,
.00398,-.00044,
.00483,-.00129,
.004897,-.001007,
.004947,-.000721,
.004981,-.000432,
.004997,-.000141,
.004997,.000149,
.00498,.00044,
.004946,.000729,
.004895,.001015,
.00483,.00129,
.00398,.00044,
90.*
4,1,15,.00044,-.00398,
.000208,-.003999,
-.000025,-.004004,
-.000258,-.003996,
-.00044,-.00398,
-.00129,-.00483,
-.001007,-.004897,
-.000721,-.004947,
-.000432,-.004981,
-.000141,-.004997,
.000149,-.004997,
.00044,-.00498,
.000729,-.004946,
.001015,-.004895,
.00129,-.00483,
.00044,-.00398,
90.*
4,1,15,-.00398,-.00044,
-.003999,-.000208,
-.004004,.000025,
-.003996,.000258,
-.00398,.00044,
-.00483,.00129,
-.004897,.001007,
-.004947,.000721,
-.004981,.000432,
-.004997,.000141,
-.004997,-.000149,
-.00498,-.00044,
-.004946,-.000729,
-.004895,-.001015,
-.00483,-.00129,
-.00398,-.00044,
90.*
4,1,15,-.00044,.00398,
-.000208,.003999,
.000025,.004004,
.000258,.003996,
.00044,.00398,
.00129,.00483,
.001007,.004897,
.000721,.004947,
.000432,.004981,
.000141,.004997,
-.000149,.004997,
-.00044,.00498,
-.000729,.004946,
-.001015,.004895,
-.00129,.00483,
-.00044,.00398,
90.*
%
%ADD19MACRO19*%
%AMMACRO11*
4,1,15,.00398,.00044,
.003999,.000208,
.004004,-.000025,
.003996,-.000258,
.00398,-.00044,
.00483,-.00129,
.004897,-.001007,
.004947,-.000721,
.004981,-.000432,
.004997,-.000141,
.004997,.000149,
.00498,.00044,
.004946,.000729,
.004895,.001015,
.00483,.00129,
.00398,.00044,
0.0*
4,1,15,.00044,-.00398,
.000208,-.003999,
-.000025,-.004004,
-.000258,-.003996,
-.00044,-.00398,
-.00129,-.00483,
-.001007,-.004897,
-.000721,-.004947,
-.000432,-.004981,
-.000141,-.004997,
.000149,-.004997,
.00044,-.00498,
.000729,-.004946,
.001015,-.004895,
.00129,-.00483,
.00044,-.00398,
0.0*
4,1,15,-.00398,-.00044,
-.003999,-.000208,
-.004004,.000025,
-.003996,.000258,
-.00398,.00044,
-.00483,.00129,
-.004897,.001007,
-.004947,.000721,
-.004981,.000432,
-.004997,.000141,
-.004997,-.000149,
-.00498,-.00044,
-.004946,-.000729,
-.004895,-.001015,
-.00483,-.00129,
-.00398,-.00044,
0.0*
4,1,15,-.00044,.00398,
-.000208,.003999,
.000025,.004004,
.000258,.003996,
.00044,.00398,
.00129,.00483,
.001007,.004897,
.000721,.004947,
.000432,.004981,
.000141,.004997,
-.000149,.004997,
-.00044,.00498,
-.000729,.004946,
-.001015,.004895,
-.00129,.00483,
-.00044,.00398,
0.0*
%
%ADD11MACRO11*%
%AMMACRO20*
4,1,15,-.00398,.00044,
-.003999,.000208,
-.004004,-.000025,
-.003996,-.000258,
-.00398,-.00044,
-.00483,-.00129,
-.004897,-.001007,
-.004947,-.000721,
-.004981,-.000432,
-.004997,-.000141,
-.004997,.000149,
-.00498,.00044,
-.004946,.000729,
-.004895,.001015,
-.00483,.00129,
-.00398,.00044,
0.0*
4,1,15,-.00044,-.00398,
-.000208,-.003999,
.000025,-.004004,
.000258,-.003996,
.00044,-.00398,
.00129,-.00483,
.001007,-.004897,
.000721,-.004947,
.000432,-.004981,
.000141,-.004997,
-.000149,-.004997,
-.00044,-.00498,
-.000729,-.004946,
-.001015,-.004895,
-.00129,-.00483,
-.00044,-.00398,
0.0*
4,1,15,.00398,-.00044,
.003999,-.000208,
.004004,.000025,
.003996,.000258,
.00398,.00044,
.00483,.00129,
.004897,.001007,
.004947,.000721,
.004981,.000432,
.004997,.000141,
.004997,-.000149,
.00498,-.00044,
.004946,-.000729,
.004895,-.001015,
.00483,-.00129,
.00398,-.00044,
0.0*
4,1,15,.00044,.00398,
.000208,.003999,
-.000025,.004004,
-.000258,.003996,
-.00044,.00398,
-.00129,.00483,
-.001007,.004897,
-.000721,.004947,
-.000432,.004981,
-.000141,.004997,
.000149,.004997,
.00044,.00498,
.000729,.004946,
.001015,.004895,
.00129,.00483,
.00044,.00398,
0.0*
%
%ADD20MACRO20*%
%ADD23C,.101*%
%ADD10C,.114*%
%ADD14C,.115*%
%ADD18C,.18*%
%ADD28C,.174*%
%AMMACRO27*
4,1,15,.00398,.00044,
.003999,.000208,
.004004,-.000025,
.003996,-.000258,
.00398,-.00044,
.00483,-.00129,
.004897,-.001007,
.004947,-.000721,
.004981,-.000432,
.004997,-.000141,
.004997,.000149,
.00498,.00044,
.004946,.000729,
.004895,.001015,
.00483,.00129,
.00398,.00044,
135.*
4,1,15,.00044,-.00398,
.000208,-.003999,
-.000025,-.004004,
-.000258,-.003996,
-.00044,-.00398,
-.00129,-.00483,
-.001007,-.004897,
-.000721,-.004947,
-.000432,-.004981,
-.000141,-.004997,
.000149,-.004997,
.00044,-.00498,
.000729,-.004946,
.001015,-.004895,
.00129,-.00483,
.00044,-.00398,
135.*
4,1,15,-.00398,-.00044,
-.003999,-.000208,
-.004004,.000025,
-.003996,.000258,
-.00398,.00044,
-.00483,.00129,
-.004897,.001007,
-.004947,.000721,
-.004981,.000432,
-.004997,.000141,
-.004997,-.000149,
-.00498,-.00044,
-.004946,-.000729,
-.004895,-.001015,
-.00483,-.00129,
-.00398,-.00044,
135.*
4,1,15,-.00044,.00398,
-.000208,.003999,
.000025,.004004,
.000258,.003996,
.00044,.00398,
.00129,.00483,
.001007,.004897,
.000721,.004947,
.000432,.004981,
.000141,.004997,
-.000149,.004997,
-.00044,.00498,
-.000729,.004946,
-.001015,.004895,
-.00129,.00483,
-.00044,.00398,
135.*
%
%ADD27MACRO27*%
%AMMACRO25*
4,1,15,.00398,.00044,
.003999,.000208,
.004004,-.000025,
.003996,-.000258,
.00398,-.00044,
.00483,-.00129,
.004897,-.001007,
.004947,-.000721,
.004981,-.000432,
.004997,-.000141,
.004997,.000149,
.00498,.00044,
.004946,.000729,
.004895,.001015,
.00483,.00129,
.00398,.00044,
270.*
4,1,15,.00044,-.00398,
.000208,-.003999,
-.000025,-.004004,
-.000258,-.003996,
-.00044,-.00398,
-.00129,-.00483,
-.001007,-.004897,
-.000721,-.004947,
-.000432,-.004981,
-.000141,-.004997,
.000149,-.004997,
.00044,-.00498,
.000729,-.004946,
.001015,-.004895,
.00129,-.00483,
.00044,-.00398,
270.*
4,1,15,-.00398,-.00044,
-.003999,-.000208,
-.004004,.000025,
-.003996,.000258,
-.00398,.00044,
-.00483,.00129,
-.004897,.001007,
-.004947,.000721,
-.004981,.000432,
-.004997,.000141,
-.004997,-.000149,
-.00498,-.00044,
-.004946,-.000729,
-.004895,-.001015,
-.00483,-.00129,
-.00398,-.00044,
270.*
4,1,15,-.00044,.00398,
-.000208,.003999,
.000025,.004004,
.000258,.003996,
.00044,.00398,
.00129,.00483,
.001007,.004897,
.000721,.004947,
.000432,.004981,
.000141,.004997,
-.000149,.004997,
-.00044,.00498,
-.000729,.004946,
-.001015,.004895,
-.00129,.00483,
-.00044,.00398,
270.*
%
%ADD25MACRO25*%
%AMMACRO24*
4,1,15,.00398,.00044,
.003999,.000208,
.004004,-.000025,
.003996,-.000258,
.00398,-.00044,
.00483,-.00129,
.004897,-.001007,
.004947,-.000721,
.004981,-.000432,
.004997,-.000141,
.004997,.000149,
.00498,.00044,
.004946,.000729,
.004895,.001015,
.00483,.00129,
.00398,.00044,
315.*
4,1,15,.00044,-.00398,
.000208,-.003999,
-.000025,-.004004,
-.000258,-.003996,
-.00044,-.00398,
-.00129,-.00483,
-.001007,-.004897,
-.000721,-.004947,
-.000432,-.004981,
-.000141,-.004997,
.000149,-.004997,
.00044,-.00498,
.000729,-.004946,
.001015,-.004895,
.00129,-.00483,
.00044,-.00398,
315.*
4,1,15,-.00398,-.00044,
-.003999,-.000208,
-.004004,.000025,
-.003996,.000258,
-.00398,.00044,
-.00483,.00129,
-.004897,.001007,
-.004947,.000721,
-.004981,.000432,
-.004997,.000141,
-.004997,-.000149,
-.00498,-.00044,
-.004946,-.000729,
-.004895,-.001015,
-.00483,-.00129,
-.00398,-.00044,
315.*
4,1,15,-.00044,.00398,
-.000208,.003999,
.000025,.004004,
.000258,.003996,
.00044,.00398,
.00129,.00483,
.001007,.004897,
.000721,.004947,
.000432,.004981,
.000141,.004997,
-.000149,.004997,
-.00044,.00498,
-.000729,.004946,
-.001015,.004895,
-.00129,.00483,
-.00044,.00398,
315.*
%
%ADD24MACRO24*%
%AMMACRO13*
4,1,15,.00398,.00044,
.003999,.000208,
.004004,-.000025,
.003996,-.000258,
.00398,-.00044,
.00483,-.00129,
.004897,-.001007,
.004947,-.000721,
.004981,-.000432,
.004997,-.000141,
.004997,.000149,
.00498,.00044,
.004946,.000729,
.004895,.001015,
.00483,.00129,
.00398,.00044,
180.*
4,1,15,.00044,-.00398,
.000208,-.003999,
-.000025,-.004004,
-.000258,-.003996,
-.00044,-.00398,
-.00129,-.00483,
-.001007,-.004897,
-.000721,-.004947,
-.000432,-.004981,
-.000141,-.004997,
.000149,-.004997,
.00044,-.00498,
.000729,-.004946,
.001015,-.004895,
.00129,-.00483,
.00044,-.00398,
180.*
4,1,15,-.00398,-.00044,
-.003999,-.000208,
-.004004,.000025,
-.003996,.000258,
-.00398,.00044,
-.00483,.00129,
-.004897,.001007,
-.004947,.000721,
-.004981,.000432,
-.004997,.000141,
-.004997,-.000149,
-.00498,-.00044,
-.004946,-.000729,
-.004895,-.001015,
-.00483,-.00129,
-.00398,-.00044,
180.*
4,1,15,-.00044,.00398,
-.000208,.003999,
.000025,.004004,
.000258,.003996,
.00044,.00398,
.00129,.00483,
.001007,.004897,
.000721,.004947,
.000432,.004981,
.000141,.004997,
-.000149,.004997,
-.00044,.00498,
-.000729,.004946,
-.001015,.004895,
-.00129,.00483,
-.00044,.00398,
180.*
%
%ADD13MACRO13*%
%AMMACRO26*
4,1,15,-.00398,.00044,
-.003999,.000208,
-.004004,-.000025,
-.003996,-.000258,
-.00398,-.00044,
-.00483,-.00129,
-.004897,-.001007,
-.004947,-.000721,
-.004981,-.000432,
-.004997,-.000141,
-.004997,.000149,
-.00498,.00044,
-.004946,.000729,
-.004895,.001015,
-.00483,.00129,
-.00398,.00044,
270.*
4,1,15,-.00044,-.00398,
-.000208,-.003999,
.000025,-.004004,
.000258,-.003996,
.00044,-.00398,
.00129,-.00483,
.001007,-.004897,
.000721,-.004947,
.000432,-.004981,
.000141,-.004997,
-.000149,-.004997,
-.00044,-.00498,
-.000729,-.004946,
-.001015,-.004895,
-.00129,-.00483,
-.00044,-.00398,
270.*
4,1,15,.00398,-.00044,
.003999,-.000208,
.004004,.000025,
.003996,.000258,
.00398,.00044,
.00483,.00129,
.004897,.001007,
.004947,.000721,
.004981,.000432,
.004997,.000141,
.004997,-.000149,
.00498,-.00044,
.004946,-.000729,
.004895,-.001015,
.00483,-.00129,
.00398,-.00044,
270.*
4,1,15,.00044,.00398,
.000208,.003999,
-.000025,.004004,
-.000258,.003996,
-.00044,.00398,
-.00129,.00483,
-.001007,.004897,
-.000721,.004947,
-.000432,.004981,
-.000141,.004997,
.000149,.004997,
.00044,.00498,
.000729,.004946,
.001015,.004895,
.00129,.00483,
.00044,.00398,
270.*
%
%ADD26MACRO26*%
%AMMACRO15*
4,1,15,-.00398,.00044,
-.003999,.000208,
-.004004,-.000025,
-.003996,-.000258,
-.00398,-.00044,
-.00483,-.00129,
-.004897,-.001007,
-.004947,-.000721,
-.004981,-.000432,
-.004997,-.000141,
-.004997,.000149,
-.00498,.00044,
-.004946,.000729,
-.004895,.001015,
-.00483,.00129,
-.00398,.00044,
180.*
4,1,15,-.00044,-.00398,
-.000208,-.003999,
.000025,-.004004,
.000258,-.003996,
.00044,-.00398,
.00129,-.00483,
.001007,-.004897,
.000721,-.004947,
.000432,-.004981,
.000141,-.004997,
-.000149,-.004997,
-.00044,-.00498,
-.000729,-.004946,
-.001015,-.004895,
-.00129,-.00483,
-.00044,-.00398,
180.*
4,1,15,.00398,-.00044,
.003999,-.000208,
.004004,.000025,
.003996,.000258,
.00398,.00044,
.00483,.00129,
.004897,.001007,
.004947,.000721,
.004981,.000432,
.004997,.000141,
.004997,-.000149,
.00498,-.00044,
.004946,-.000729,
.004895,-.001015,
.00483,-.00129,
.00398,-.00044,
180.*
4,1,15,.00044,.00398,
.000208,.003999,
-.000025,.004004,
-.000258,.003996,
-.00044,.00398,
-.00129,.00483,
-.001007,.004897,
-.000721,.004947,
-.000432,.004981,
-.000141,.004997,
.000149,.004997,
.00044,.00498,
.000729,.004946,
.001015,.004895,
.00129,.00483,
.00044,.00398,
180.*
%
%ADD15MACRO15*%
%ADD29C,.02*%
%ADD30C,.006*%
%ADD34C,.09704*%
%ADD33C,.11004*%
%ADD31C,.11104*%
%ADD55C,.17004*%
%ADD46R,.04602X.047*%
%ADD43R,.047X.04602*%
%ADD39R,.04702X.04602*%
%ADD45R,.04602X.04704*%
%ADD38R,.04704X.04602*%
%ADD32C,.39404*%
%ADD47R,.04706X.04602*%
%ADD40R,.0469X.04602*%
%ADD53R,.04664X.04602*%
%ADD54R,.04672X.04604*%
%ADD52R,.04692X.04602*%
%ADD51R,.04566X.04602*%
%ADD36R,.04684X.04602*%
%ADD48R,.04602X.04694*%
%ADD42R,.04676X.04602*%
%ADD41R,.04694X.04602*%
%ADD44R,.04696X.04602*%
%ADD35R,.04602X.04696*%
%ADD50R,.04688X.04602*%
%ADD49R,.04602X.04698*%
%ADD37R,.04698X.04602*%
G75*
%LPD*%
G75*
G36*
G01X-6000Y-6000D02*
X1043402D01*
Y1998126D01*
X-6000D01*
Y-6000D01*
G37*
%LPC*%
G75*
G36*
G01X124665Y13315D02*
X119419Y3004D01*
X3937D01*
G02X3004Y3937I0J933D01*
G01Y596998D01*
X13760D01*
Y734169D01*
X17323D01*
G03Y748839I0J7335D01*
G01X13760D01*
Y924002D01*
X3004D01*
Y1092998D01*
X13760D01*
Y1230232D01*
X17323D01*
G03Y1244902I0J7335D01*
G01X13760D01*
Y1420002D01*
X3004D01*
Y1510498D01*
X13760D01*
Y1647555D01*
X17323D01*
G03Y1662224I0J7335D01*
G01X13760D01*
Y1838002D01*
X3004D01*
Y1988189D01*
G02X3937Y1989122I933J0D01*
G01X1033465D01*
G02X1034398Y1988189I0J-933D01*
G01Y1686599D01*
X1032220Y1684421D01*
X1028700D01*
G03X1020224Y1675945I0J-8476D01*
G01Y1621265D01*
X1018046Y1619087D01*
X993681D01*
G03Y1608866I0J-5110D01*
G01X1018046D01*
X1020224Y1606688D01*
Y1434291D01*
G03X1028700Y1425815I8477J1D01*
G01X1032220D01*
X1034398Y1423637D01*
Y3937D01*
G02X1033465Y3004I-933J0D01*
G01X148298D01*
X143084Y13251D01*
G02X142768Y14565I2585J1317D01*
G01Y17717D01*
G03X124949I-8909J0D01*
G01Y14565D01*
G02X124665Y13315I-2902J2D01*
G37*
%LPD*%
G75*
G36*
G01X1005938Y1903534D02*
Y1900889D01*
G03X1007242Y1897199I5875J1D01*
G02X988819I-9211J-7446D01*
G03X990122Y1900889I-4571J3689D01*
G01Y1903534D01*
G02X1005938I7908J0D01*
G37*
G36*
G01Y1082667D02*
Y1080022D01*
G03X1007242Y1076332I5875J1D01*
G02X988819I-9211J-7446D01*
G03X990122Y1080022I-4571J3689D01*
G01Y1082667D01*
G02X1005938I7908J0D01*
G37*
G36*
G01Y686998D02*
Y684353D01*
G03X1007242Y680663I5875J1D01*
G02X988819I-9211J-7446D01*
G03X990122Y684353I-4571J3689D01*
G01Y686998D01*
G02X1005938I7908J0D01*
G37*
G36*
G01Y163376D02*
Y160731D01*
G03X1007242Y157041I5875J1D01*
G02X988819I-9211J-7446D01*
G03X990122Y160731I-4571J3689D01*
G01Y163376D01*
G02X1005938I7908J0D01*
G37*
G36*
G01X920858Y1860549D02*
G02X916834I-2012J0D01*
G01Y1863750D01*
G02X920858Y1863749I2012J-1D01*
G01Y1860549D01*
G37*
G36*
G01Y1455037D02*
G02X916834I-2012J0D01*
G01Y1458238D01*
G02X920858Y1458237I2012J-1D01*
G01Y1455037D01*
G37*
G36*
G01Y1049525D02*
G02X916834I-2012J0D01*
G01Y1052726D01*
G02X920858Y1052725I2012J-1D01*
G01Y1049525D01*
G37*
G36*
G01Y644013D02*
G02X916834I-2012J0D01*
G01Y647214D01*
G02X920858Y647213I2012J-1D01*
G01Y644013D01*
G37*
G36*
G01Y238501D02*
G02X916834I-2012J0D01*
G01Y241702D01*
G02X920858Y241701I2012J-1D01*
G01Y238501D01*
G37*
G36*
G01X865430Y1909435D02*
G02X869452I2011J0D01*
G01Y1906234D01*
G02X865430Y1906235I-2011J1D01*
G01Y1909435D01*
G37*
G36*
G01X886628Y1892664D02*
Y1885213D01*
X886627Y1885212D01*
X878726D01*
Y1892664D01*
X886628D01*
G37*
G36*
G01Y1902112D02*
Y1894661D01*
X886627Y1894660D01*
X878726D01*
Y1902112D01*
X886628D01*
G37*
G36*
G01X878726Y1904108D02*
Y1911560D01*
X878727Y1911562D01*
X886628D01*
Y1904108D01*
X878726D01*
G37*
G36*
G01X886628Y1921010D02*
Y1913559D01*
X886627Y1913558D01*
X878726D01*
Y1921010D01*
X886628D01*
G37*
G36*
G01X865430Y1890538D02*
G02X869452I2011J0D01*
G01Y1887337D01*
G02X865430Y1887338I-2011J1D01*
G01Y1890538D01*
G37*
G36*
G01X870530Y1919484D02*
G02X875352I2411J0D01*
G01Y1915083D01*
G02X870530Y1915084I-2411J1D01*
G01Y1919484D01*
G37*
G36*
G01Y1900586D02*
G02X875352I2411J0D01*
G01Y1896185D01*
G02X870530Y1896186I-2411J1D01*
G01Y1900586D01*
G37*
G36*
G01X886628Y1930460D02*
Y1923008D01*
X886627Y1923006D01*
X878726D01*
Y1930460D01*
X886628D01*
G37*
G36*
G01Y1939908D02*
Y1932457D01*
X886627Y1932456D01*
X878726D01*
Y1939908D01*
X886628D01*
G37*
G36*
G01X865430Y1928333D02*
G02X869452I2011J0D01*
G01Y1925132D01*
G02X865430Y1925133I-2011J1D01*
G01Y1928333D01*
G37*
G36*
G01X870530Y1938382D02*
G02X875352I2411J0D01*
G01Y1933981D01*
G02X870530Y1933982I-2411J1D01*
G01Y1938382D01*
G37*
G36*
G01X865430Y1840144D02*
G02X869452I2011J0D01*
G01Y1836943D01*
G02X865430Y1836944I-2011J1D01*
G01Y1840144D01*
G37*
G36*
G01X886628Y1832822D02*
Y1825370D01*
X886627Y1825368D01*
X878726D01*
Y1832822D01*
X886628D01*
G37*
G36*
G01Y1842270D02*
Y1834819D01*
X886627Y1834818D01*
X878726D01*
Y1842270D01*
X886628D01*
G37*
G36*
G01X899188Y1865892D02*
Y1858441D01*
X899186Y1858440D01*
X891284D01*
Y1865892D01*
X899188D01*
G37*
G36*
G01X886628Y1851718D02*
Y1844268D01*
X886627Y1844266D01*
X878726D01*
Y1851718D01*
X886628D01*
G37*
G36*
G01X870530Y1850193D02*
G02X875352I2411J0D01*
G01Y1845792D01*
G02X870530Y1845793I-2411J1D01*
G01Y1850193D01*
G37*
G36*
G01X905146Y1855430D02*
G02Y1859454I0J2012D01*
G01X908347D01*
G02X908346Y1855430I-1J-2012D01*
G01X905146D01*
G37*
G36*
G01X886628Y1515498D02*
Y1508047D01*
X886627Y1508046D01*
X878726D01*
Y1515498D01*
X886628D01*
G37*
G36*
G01Y1524948D02*
Y1517496D01*
X886627Y1517494D01*
X878726D01*
Y1524948D01*
X886628D01*
G37*
G36*
G01Y1534396D02*
Y1526945D01*
X886627Y1526944D01*
X878726D01*
Y1534396D01*
X886628D01*
G37*
G36*
G01X865430Y1522821D02*
G02X869452I2011J0D01*
G01Y1519620D01*
G02X865430Y1519621I-2011J1D01*
G01Y1522821D01*
G37*
G36*
G01X870530Y1532870D02*
G02X875352I2411J0D01*
G01Y1528469D01*
G02X870530Y1528470I-2411J1D01*
G01Y1532870D01*
G37*
G36*
G01Y1513972D02*
G02X875352I2411J0D01*
G01Y1509571D01*
G02X870530Y1509572I-2411J1D01*
G01Y1513972D01*
G37*
G36*
G01X886628Y1446206D02*
Y1438756D01*
X886627Y1438754D01*
X878726D01*
Y1446206D01*
X886628D01*
G37*
G36*
G01X899188Y1460380D02*
Y1452929D01*
X899186Y1452928D01*
X891284D01*
Y1460380D01*
X899188D01*
G37*
G36*
G01X886628Y1487152D02*
Y1479701D01*
X886627Y1479700D01*
X878726D01*
Y1487152D01*
X886628D01*
G37*
G36*
G01X865430Y1485026D02*
G02X869452I2011J0D01*
G01Y1481825D01*
G02X865430Y1481826I-2011J1D01*
G01Y1485026D01*
G37*
G36*
G01X870530Y1444681D02*
G02X875352I2411J0D01*
G01Y1440280D01*
G02X870530Y1440281I-2411J1D01*
G01Y1444681D01*
G37*
G36*
G01X886628Y1496600D02*
Y1489149D01*
X886627Y1489148D01*
X878726D01*
Y1496600D01*
X886628D01*
G37*
G36*
G01Y1506050D02*
Y1498598D01*
X886627Y1498596D01*
X878726D01*
Y1506050D01*
X886628D01*
G37*
G36*
G01X865430Y1503923D02*
G02X869452I2011J0D01*
G01Y1500722D01*
G02X865430Y1500723I-2011J1D01*
G01Y1503923D01*
G37*
G36*
G01X870530Y1495074D02*
G02X875352I2411J0D01*
G01Y1490673D01*
G02X870530Y1490674I-2411J1D01*
G01Y1495074D01*
G37*
G36*
G01X905146Y1449918D02*
G02Y1453942I0J2012D01*
G01X908347D01*
G02X908346Y1449918I-1J-2012D01*
G01X905146D01*
G37*
G36*
G01X886628Y1427310D02*
Y1419858D01*
X886627Y1419856D01*
X878726D01*
Y1427310D01*
X886628D01*
G37*
G36*
G01Y1436758D02*
Y1429307D01*
X886627Y1429306D01*
X878726D01*
Y1436758D01*
X886628D01*
G37*
G36*
G01X865430Y1434632D02*
G02X869452I2011J0D01*
G01Y1431431D01*
G02X865430Y1431432I-2011J1D01*
G01Y1434632D01*
G37*
G36*
G01Y1098411D02*
G02X869452I2011J0D01*
G01Y1095210D01*
G02X865430Y1095211I-2011J1D01*
G01Y1098411D01*
G37*
G36*
G01Y1117309D02*
G02X869452I2011J0D01*
G01Y1114108D01*
G02X865430Y1114109I-2011J1D01*
G01Y1117309D01*
G37*
G36*
G01X870530Y1108460D02*
G02X875352I2411J0D01*
G01Y1104059D01*
G02X870530Y1104060I-2411J1D01*
G01Y1108460D01*
G37*
G36*
G01Y1089562D02*
G02X875352I2411J0D01*
G01Y1085161D01*
G02X870530Y1085162I-2411J1D01*
G01Y1089562D01*
G37*
G36*
G01X886628Y1081640D02*
Y1074189D01*
X886627Y1074188D01*
X878726D01*
Y1081640D01*
X886628D01*
G37*
G36*
G01Y1091088D02*
Y1083637D01*
X886627Y1083636D01*
X878726D01*
Y1091088D01*
X886628D01*
G37*
G36*
G01Y1100538D02*
Y1093086D01*
X886627Y1093084D01*
X878726D01*
Y1100538D01*
X886628D01*
G37*
G36*
G01Y1109986D02*
Y1102535D01*
X886627Y1102534D01*
X878726D01*
Y1109986D01*
X886628D01*
G37*
G36*
G01Y1119436D02*
Y1111984D01*
X886627Y1111982D01*
X878726D01*
Y1119436D01*
X886628D01*
G37*
G36*
G01X865430Y1079514D02*
G02X869452I2011J0D01*
G01Y1076313D01*
G02X865430Y1076314I-2011J1D01*
G01Y1079514D01*
G37*
G36*
G01X886628Y1128884D02*
Y1121433D01*
X886627Y1121432D01*
X878726D01*
Y1128884D01*
X886628D01*
G37*
G36*
G01X870530Y1127358D02*
G02X875352I2411J0D01*
G01Y1122957D01*
G02X870530Y1122958I-2411J1D01*
G01Y1127358D01*
G37*
G36*
G01X886628Y1021798D02*
Y1014346D01*
X886627Y1014344D01*
X878726D01*
Y1021798D01*
X886628D01*
G37*
G36*
G01Y1031246D02*
Y1023795D01*
X886627Y1023794D01*
X878726D01*
Y1031246D01*
X886628D01*
G37*
G36*
G01X878726Y1033242D02*
Y1040693D01*
X878727Y1040694D01*
X886628D01*
Y1033242D01*
X878726D01*
G37*
G36*
G01X899188Y1054868D02*
Y1047417D01*
X899186Y1047416D01*
X891284D01*
Y1054868D01*
X899188D01*
G37*
G36*
G01X865430Y1029120D02*
G02X869452I2011J0D01*
G01Y1025919D01*
G02X865430Y1025920I-2011J1D01*
G01Y1029120D01*
G37*
G36*
G01X870530Y1039169D02*
G02X875352I2411J0D01*
G01Y1034768D01*
G02X870530Y1034769I-2411J1D01*
G01Y1039169D01*
G37*
G36*
G01X905146Y1044406D02*
G02Y1048430I0J2012D01*
G01X908347D01*
G02X908346Y1044406I-1J-2012D01*
G01X905146D01*
G37*
G36*
G01X886628Y713924D02*
Y706472D01*
X886627Y706470D01*
X878726D01*
Y713924D01*
X886628D01*
G37*
G36*
G01Y723372D02*
Y715921D01*
X886627Y715920D01*
X878726D01*
Y723372D01*
X886628D01*
G37*
G36*
G01X865430Y711797D02*
G02X869452I2011J0D01*
G01Y708596D01*
G02X865430Y708597I-2011J1D01*
G01Y711797D01*
G37*
G36*
G01X870530Y721846D02*
G02X875352I2411J0D01*
G01Y717445D01*
G02X870530Y717446I-2411J1D01*
G01Y721846D01*
G37*
G36*
G01X899188Y649356D02*
Y641905D01*
X899186Y641904D01*
X891284D01*
Y649356D01*
X899188D01*
G37*
G36*
G01X886628Y676128D02*
Y668677D01*
X886627Y668676D01*
X878726D01*
Y676128D01*
X886628D01*
G37*
G36*
G01Y685576D02*
Y678125D01*
X886627Y678124D01*
X878726D01*
Y685576D01*
X886628D01*
G37*
G36*
G01X865430Y674002D02*
G02X869452I2011J0D01*
G01Y670801D01*
G02X865430Y670802I-2011J1D01*
G01Y674002D01*
G37*
G36*
G01X870530Y684050D02*
G02X875352I2411J0D01*
G01Y679649D01*
G02X870530Y679650I-2411J1D01*
G01Y684050D01*
G37*
G36*
G01X865430Y692899D02*
G02X869452I2011J0D01*
G01Y689698D01*
G02X865430Y689699I-2011J1D01*
G01Y692899D01*
G37*
G36*
G01X870530Y702948D02*
G02X875352I2411J0D01*
G01Y698547D01*
G02X870530Y698548I-2411J1D01*
G01Y702948D01*
G37*
G36*
G01X886628Y695026D02*
Y687574D01*
X886627Y687572D01*
X878726D01*
Y695026D01*
X886628D01*
G37*
G36*
G01Y704474D02*
Y697023D01*
X886627Y697022D01*
X878726D01*
Y704474D01*
X886628D01*
G37*
G36*
G01X905146Y638894D02*
G02Y642918I0J2012D01*
G01X908347D01*
G02X908346Y638894I-1J-2012D01*
G01X905146D01*
G37*
G36*
G01X886628Y616286D02*
Y608834D01*
X886627Y608832D01*
X878726D01*
Y616286D01*
X886628D01*
G37*
G36*
G01Y625734D02*
Y618283D01*
X886627Y618282D01*
X878726D01*
Y625734D01*
X886628D01*
G37*
G36*
G01Y635182D02*
Y627732D01*
X886627Y627730D01*
X878726D01*
Y635182D01*
X886628D01*
G37*
G36*
G01X865430Y623608D02*
G02X869452I2011J0D01*
G01Y620407D01*
G02X865430Y620408I-2011J1D01*
G01Y623608D01*
G37*
G36*
G01X870530Y633657D02*
G02X875352I2411J0D01*
G01Y629256D01*
G02X870530Y629257I-2411J1D01*
G01Y633657D01*
G37*
G36*
G01X865430Y287387D02*
G02X869452I2011J0D01*
G01Y284186D01*
G02X865430Y284187I-2011J1D01*
G01Y287387D01*
G37*
G36*
G01Y306285D02*
G02X869452I2011J0D01*
G01Y303084D01*
G02X865430Y303085I-2011J1D01*
G01Y306285D01*
G37*
G36*
G01X870530Y316334D02*
G02X875352I2411J0D01*
G01Y311933D01*
G02X870530Y311934I-2411J1D01*
G01Y316334D01*
G37*
G36*
G01Y297436D02*
G02X875352I2411J0D01*
G01Y293035D01*
G02X870530Y293036I-2411J1D01*
G01Y297436D01*
G37*
G36*
G01Y278538D02*
G02X875352I2411J0D01*
G01Y274137D01*
G02X870530Y274138I-2411J1D01*
G01Y278538D01*
G37*
G36*
G01X886628Y280064D02*
Y272613D01*
X886627Y272612D01*
X878726D01*
Y280064D01*
X886628D01*
G37*
G36*
G01Y289514D02*
Y282062D01*
X886627Y282060D01*
X878726D01*
Y289514D01*
X886628D01*
G37*
G36*
G01Y298962D02*
Y291511D01*
X886627Y291510D01*
X878726D01*
Y298962D01*
X886628D01*
G37*
G36*
G01Y308412D02*
Y300960D01*
X886627Y300958D01*
X878726D01*
Y308412D01*
X886628D01*
G37*
G36*
G01Y317860D02*
Y310409D01*
X886627Y310408D01*
X878726D01*
Y317860D01*
X886628D01*
G37*
G36*
G01X865430Y218096D02*
G02X869452I2011J0D01*
G01Y214895D01*
G02X865430Y214896I-2011J1D01*
G01Y218096D01*
G37*
G36*
G01X870530Y228145D02*
G02X875352I2411J0D01*
G01Y223744D01*
G02X870530Y223745I-2411J1D01*
G01Y228145D01*
G37*
G36*
G01X886628Y210774D02*
Y203322D01*
X886627Y203320D01*
X878726D01*
Y210774D01*
X886628D01*
G37*
G36*
G01Y220222D02*
Y212771D01*
X886627Y212770D01*
X878726D01*
Y220222D01*
X886628D01*
G37*
G36*
G01Y229670D02*
Y222220D01*
X886627Y222218D01*
X878726D01*
Y229670D01*
X886628D01*
G37*
G36*
G01X891284Y236392D02*
Y243843D01*
X891286Y243844D01*
X899188D01*
Y236392D01*
X891284D01*
G37*
G36*
G01X865430Y268490D02*
G02X869452I2011J0D01*
G01Y265289D01*
G02X865430Y265290I-2011J1D01*
G01Y268490D01*
G37*
G36*
G01X886628Y270616D02*
Y263165D01*
X886627Y263164D01*
X878726D01*
Y270616D01*
X886628D01*
G37*
G36*
G01X905146Y233382D02*
G02Y237406I0J2012D01*
G01X908347D01*
G02X908346Y233382I-1J-2012D01*
G01X905146D01*
G37*
G36*
G01X354800Y1731198D02*
G02X354398Y1731600I0J402D01*
G01Y1736400D01*
G02X354800Y1736802I402J0D01*
G01X360200D01*
G02X360602Y1736400I0J-402D01*
G01Y1731600D01*
G02X360200Y1731198I-402J0D01*
G01X354800D01*
G37*
G36*
G01X339800D02*
G02X339398Y1731600I0J402D01*
G01Y1736400D01*
G02X339800Y1736802I402J0D01*
G01X345200D01*
G02X345602Y1736400I0J-402D01*
G01Y1731600D01*
G02X345200Y1731198I-402J0D01*
G01X339800D01*
G37*
G36*
G01X401198Y1710700D02*
G02X401600Y1711102I402J0D01*
G01X406400D01*
G02X406802Y1710700I0J-402D01*
G01Y1705300D01*
G02X406400Y1704898I-402J0D01*
G01X401600D01*
G02X401198Y1705300I0J402D01*
G01Y1710700D01*
G37*
G36*
G01Y1725700D02*
G02X401600Y1726102I402J0D01*
G01X406400D01*
G02X406802Y1725700I0J-402D01*
G01Y1720300D01*
G02X406400Y1719898I-402J0D01*
G01X401600D01*
G02X401198Y1720300I0J402D01*
G01Y1725700D01*
G37*
G36*
G01X354800Y1663198D02*
G02X354398Y1663600I0J402D01*
G01Y1668400D01*
G02X354800Y1668802I402J0D01*
G01X360200D01*
G02X360602Y1668400I0J-402D01*
G01Y1663600D01*
G02X360200Y1663198I-402J0D01*
G01X354800D01*
G37*
G36*
G01X339800D02*
G02X339398Y1663600I0J402D01*
G01Y1668400D01*
G02X339800Y1668802I402J0D01*
G01X345200D01*
G02X345602Y1668400I0J-402D01*
G01Y1663600D01*
G02X345200Y1663198I-402J0D01*
G01X339800D01*
G37*
G36*
G01X401198Y1227200D02*
G02X401600Y1227602I402J0D01*
G01X406400D01*
G02X406802Y1227200I0J-402D01*
G01Y1221800D01*
G02X406400Y1221398I-402J0D01*
G01X401600D01*
G02X401198Y1221800I0J402D01*
G01Y1227200D01*
G37*
G36*
G01X390300Y1232698D02*
G02X389898Y1233100I0J402D01*
G01Y1237900D01*
G02X390300Y1238302I402J0D01*
G01X395700D01*
G02X396102Y1237900I0J-402D01*
G01Y1233100D01*
G02X395700Y1232698I-402J0D01*
G01X390300D01*
G37*
G36*
G01X375300D02*
G02X374898Y1233100I0J402D01*
G01Y1237900D01*
G02X375300Y1238302I402J0D01*
G01X380700D01*
G02X381102Y1237900I0J-402D01*
G01Y1233100D01*
G02X380700Y1232698I-402J0D01*
G01X375300D01*
G37*
G36*
G01X354800D02*
G02X354398Y1233100I0J402D01*
G01Y1237900D01*
G02X354800Y1238302I402J0D01*
G01X360200D01*
G02X360602Y1237900I0J-402D01*
G01Y1233100D01*
G02X360200Y1232698I-402J0D01*
G01X354800D01*
G37*
G36*
G01X339800D02*
G02X339398Y1233100I0J402D01*
G01Y1237900D01*
G02X339800Y1238302I402J0D01*
G01X345200D01*
G02X345602Y1237900I0J-402D01*
G01Y1233100D01*
G02X345200Y1232698I-402J0D01*
G01X339800D01*
G37*
G36*
G01X338112Y1197950D02*
G02X337900Y1197738I-212J0D01*
G01X337100D01*
G02X336888Y1197950I0J212D01*
G01Y1198950D01*
G02X337100Y1199162I212J0D01*
G01X337900D01*
G02X338112Y1198950I0J-212D01*
G01Y1197950D01*
G37*
G36*
G01Y1200150D02*
G02X337900Y1199938I-212J0D01*
G01X337100D01*
G02X336888Y1200150I0J212D01*
G01Y1201150D01*
G02X337100Y1201362I212J0D01*
G01X337900D01*
G02X338112Y1201150I0J-212D01*
G01Y1200150D01*
G37*
G36*
G01X401198Y1212200D02*
G02X401600Y1212602I402J0D01*
G01X406400D01*
G02X406802Y1212200I0J-402D01*
G01Y1206800D01*
G02X406400Y1206398I-402J0D01*
G01X401600D01*
G02X401198Y1206800I0J402D01*
G01Y1212200D01*
G37*
G36*
G01X390300Y1164698D02*
G02X389898Y1165100I0J402D01*
G01Y1169900D01*
G02X390300Y1170302I402J0D01*
G01X395700D01*
G02X396102Y1169900I0J-402D01*
G01Y1165100D01*
G02X395700Y1164698I-402J0D01*
G01X390300D01*
G37*
G36*
G01X375300D02*
G02X374898Y1165100I0J402D01*
G01Y1169900D01*
G02X375300Y1170302I402J0D01*
G01X380700D01*
G02X381102Y1169900I0J-402D01*
G01Y1165100D01*
G02X380700Y1164698I-402J0D01*
G01X375300D01*
G37*
G36*
G01X390300Y861198D02*
G02X389898Y861600I0J402D01*
G01Y866400D01*
G02X390300Y866802I402J0D01*
G01X395700D01*
G02X396102Y866400I0J-402D01*
G01Y861600D01*
G02X395700Y861198I-402J0D01*
G01X390300D01*
G37*
G36*
G01X375300D02*
G02X374898Y861600I0J402D01*
G01Y866400D01*
G02X375300Y866802I402J0D01*
G01X380700D01*
G02X381102Y866400I0J-402D01*
G01Y861600D01*
G02X380700Y861198I-402J0D01*
G01X375300D01*
G37*
G36*
G01X354800D02*
G02X354398Y861600I0J402D01*
G01Y866400D01*
G02X354800Y866802I402J0D01*
G01X360200D01*
G02X360602Y866400I0J-402D01*
G01Y861600D01*
G02X360200Y861198I-402J0D01*
G01X354800D01*
G37*
G36*
G01X339800D02*
G02X339398Y861600I0J402D01*
G01Y866400D01*
G02X339800Y866802I402J0D01*
G01X345200D01*
G02X345602Y866400I0J-402D01*
G01Y861600D01*
G02X345200Y861198I-402J0D01*
G01X339800D01*
G37*
G36*
G01X337412Y826450D02*
G02X337200Y826238I-212J0D01*
G01X336400D01*
G02X336188Y826450I0J212D01*
G01Y827450D01*
G02X336400Y827662I212J0D01*
G01X337200D01*
G02X337412Y827450I0J-212D01*
G01Y826450D01*
G37*
G36*
G01Y828650D02*
G02X337200Y828438I-212J0D01*
G01X336400D01*
G02X336188Y828650I0J212D01*
G01Y829650D01*
G02X336400Y829862I212J0D01*
G01X337200D01*
G02X337412Y829650I0J-212D01*
G01Y828650D01*
G37*
G36*
G01X401198Y809700D02*
G02X401600Y810102I402J0D01*
G01X406400D01*
G02X406802Y809700I0J-402D01*
G01Y804300D01*
G02X406400Y803898I-402J0D01*
G01X401600D01*
G02X401198Y804300I0J402D01*
G01Y809700D01*
G37*
G36*
G01Y824700D02*
G02X401600Y825102I402J0D01*
G01X406400D01*
G02X406802Y824700I0J-402D01*
G01Y819300D01*
G02X406400Y818898I-402J0D01*
G01X401600D01*
G02X401198Y819300I0J402D01*
G01Y824700D01*
G37*
G36*
G01X383800Y793198D02*
G02X383398Y793600I0J402D01*
G01Y798400D01*
G02X383800Y798802I402J0D01*
G01X389200D01*
G02X389602Y798400I0J-402D01*
G01Y793600D01*
G02X389200Y793198I-402J0D01*
G01X383800D01*
G37*
G36*
G01X368800D02*
G02X368398Y793600I0J402D01*
G01Y798400D01*
G02X368800Y798802I402J0D01*
G01X374200D01*
G02X374602Y798400I0J-402D01*
G01Y793600D01*
G02X374200Y793198I-402J0D01*
G01X368800D01*
G37*
G36*
G01X390300Y431198D02*
G02X389898Y431600I0J402D01*
G01Y436400D01*
G02X390300Y436802I402J0D01*
G01X395700D01*
G02X396102Y436400I0J-402D01*
G01Y431600D01*
G02X395700Y431198I-402J0D01*
G01X390300D01*
G37*
G36*
G01X375300D02*
G02X374898Y431600I0J402D01*
G01Y436400D01*
G02X375300Y436802I402J0D01*
G01X380700D01*
G02X381102Y436400I0J-402D01*
G01Y431600D01*
G02X380700Y431198I-402J0D01*
G01X375300D01*
G37*
G36*
G01X354800D02*
G02X354398Y431600I0J402D01*
G01Y436400D01*
G02X354800Y436802I402J0D01*
G01X360200D01*
G02X360602Y436400I0J-402D01*
G01Y431600D01*
G02X360200Y431198I-402J0D01*
G01X354800D01*
G37*
G36*
G01X339800D02*
G02X339398Y431600I0J402D01*
G01Y436400D01*
G02X339800Y436802I402J0D01*
G01X345200D01*
G02X345602Y436400I0J-402D01*
G01Y431600D01*
G02X345200Y431198I-402J0D01*
G01X339800D01*
G37*
G36*
G01X338412Y397000D02*
G02X338200Y396788I-212J0D01*
G01X337400D01*
G02X337188Y397000I0J212D01*
G01Y398000D01*
G02X337400Y398212I212J0D01*
G01X338200D01*
G02X338412Y398000I0J-212D01*
G01Y397000D01*
G37*
G36*
G01Y399200D02*
G02X338200Y398988I-212J0D01*
G01X337400D01*
G02X337188Y399200I0J212D01*
G01Y400200D01*
G02X337400Y400412I212J0D01*
G01X338200D01*
G02X338412Y400200I0J-212D01*
G01Y399200D01*
G37*
G36*
G01X390300Y363198D02*
G02X389898Y363600I0J402D01*
G01Y368400D01*
G02X390300Y368802I402J0D01*
G01X395700D01*
G02X396102Y368400I0J-402D01*
G01Y363600D01*
G02X395700Y363198I-402J0D01*
G01X390300D01*
G37*
G36*
G01X375300D02*
G02X374898Y363600I0J402D01*
G01Y368400D01*
G02X375300Y368802I402J0D01*
G01X380700D01*
G02X381102Y368400I0J-402D01*
G01Y363600D01*
G02X380700Y363198I-402J0D01*
G01X375300D01*
G37*
G36*
G01X354800D02*
G02X354398Y363600I0J402D01*
G01Y368400D01*
G02X354800Y368802I402J0D01*
G01X360200D01*
G02X360602Y368400I0J-402D01*
G01Y363600D01*
G02X360200Y363198I-402J0D01*
G01X354800D01*
G37*
G36*
G01X339800D02*
G02X339398Y363600I0J402D01*
G01Y368400D01*
G02X339800Y368802I402J0D01*
G01X345200D01*
G02X345602Y368400I0J-402D01*
G01Y363600D01*
G02X345200Y363198I-402J0D01*
G01X339800D01*
G37*
G36*
G01X283498Y1903534D02*
Y1900889D01*
G03X284802Y1897199I5875J1D01*
G02X266379I-9211J-7446D01*
G03X267682Y1900889I-4571J3689D01*
G01Y1903534D01*
G02X283498I7908J0D01*
G37*
G36*
G01X306900Y1701162D02*
G02X307312Y1700750I0J-412D01*
G01Y1699350D01*
G02X306900Y1698938I-412J0D01*
G01X305500D01*
G02X305088Y1699350I0J412D01*
G01Y1700750D01*
G02X305500Y1701162I412J0D01*
G01X306900D01*
G37*
G36*
G01X305500Y1694838D02*
G02X305088Y1695250I0J412D01*
G01Y1696650D01*
G02X305500Y1697062I412J0D01*
G01X306900D01*
G02X307312Y1696650I0J-412D01*
G01Y1695250D01*
G02X306900Y1694838I-412J0D01*
G01X305500D01*
G37*
G36*
G01X311000Y1697062D02*
G02X311412Y1696650I0J-412D01*
G01Y1695250D01*
G02X311000Y1694838I-412J0D01*
G01X309600D01*
G02X309188Y1695250I0J412D01*
G01Y1696650D01*
G02X309600Y1697062I412J0D01*
G01X311000D01*
G37*
G36*
G01X309600Y1698938D02*
G02X309188Y1699350I0J412D01*
G01Y1700750D01*
G02X309600Y1701162I412J0D01*
G01X311000D01*
G02X311412Y1700750I0J-412D01*
G01Y1699350D01*
G02X311000Y1698938I-412J0D01*
G01X309600D01*
G37*
G36*
G01X329212Y1696450D02*
G02X329000Y1696238I-212J0D01*
G01X328200D01*
G02X327988Y1696450I0J212D01*
G01Y1697450D01*
G02X328200Y1697662I212J0D01*
G01X329000D01*
G02X329212Y1697450I0J-212D01*
G01Y1696450D01*
G37*
G36*
G01Y1698650D02*
G02X329000Y1698438I-212J0D01*
G01X328200D01*
G02X327988Y1698650I0J212D01*
G01Y1699650D01*
G02X328200Y1699862I212J0D01*
G01X329000D01*
G02X329212Y1699650I0J-212D01*
G01Y1698650D01*
G37*
G36*
G01X295600Y1695412D02*
G02Y1691388I0J-2012D01*
G01X292399D01*
G02X292400Y1695412I1J2012D01*
G01X295600D01*
G37*
G36*
G01X282988Y1700600D02*
G02X287012I2012J0D01*
G01Y1697399D01*
G02X282988Y1697400I-2012J1D01*
G01Y1700600D01*
G37*
G36*
G01X305900Y1202662D02*
G02X306312Y1202250I0J-412D01*
G01Y1200850D01*
G02X305900Y1200438I-412J0D01*
G01X304500D01*
G02X304088Y1200850I0J412D01*
G01Y1202250D01*
G02X304500Y1202662I412J0D01*
G01X305900D01*
G37*
G36*
G01X304500Y1196338D02*
G02X304088Y1196750I0J412D01*
G01Y1198150D01*
G02X304500Y1198562I412J0D01*
G01X305900D01*
G02X306312Y1198150I0J-412D01*
G01Y1196750D01*
G02X305900Y1196338I-412J0D01*
G01X304500D01*
G37*
G36*
G01X310000Y1198562D02*
G02X310412Y1198150I0J-412D01*
G01Y1196750D01*
G02X310000Y1196338I-412J0D01*
G01X308600D01*
G02X308188Y1196750I0J412D01*
G01Y1198150D01*
G02X308600Y1198562I412J0D01*
G01X310000D01*
G37*
G36*
G01X308600Y1200438D02*
G02X308188Y1200850I0J412D01*
G01Y1202250D01*
G02X308600Y1202662I412J0D01*
G01X310000D01*
G02X310412Y1202250I0J-412D01*
G01Y1200850D01*
G02X310000Y1200438I-412J0D01*
G01X308600D01*
G37*
G36*
G01X283498Y1088573D02*
Y1085928D01*
G03X284802Y1082238I5875J1D01*
G02X266379I-9211J-7446D01*
G03X267682Y1085928I-4571J3689D01*
G01Y1088573D01*
G02X283498I7908J0D01*
G37*
G36*
G01X309300Y827112D02*
G02X309712Y826700I0J-412D01*
G01Y825300D01*
G02X309300Y824888I-412J0D01*
G01X307900D01*
G02X307488Y825300I0J412D01*
G01Y826700D01*
G02X307900Y827112I412J0D01*
G01X309300D01*
G37*
G36*
G01X303800Y824888D02*
G02X303388Y825300I0J412D01*
G01Y826700D01*
G02X303800Y827112I412J0D01*
G01X305200D01*
G02X305612Y826700I0J-412D01*
G01Y825300D01*
G02X305200Y824888I-412J0D01*
G01X303800D01*
G37*
G36*
G01X305200Y831212D02*
G02X305612Y830800I0J-412D01*
G01Y829400D01*
G02X305200Y828988I-412J0D01*
G01X303800D01*
G02X303388Y829400I0J412D01*
G01Y830800D01*
G02X303800Y831212I412J0D01*
G01X305200D01*
G37*
G36*
G01X307900Y828988D02*
G02X307488Y829400I0J412D01*
G01Y830800D01*
G02X307900Y831212I412J0D01*
G01X309300D01*
G02X309712Y830800I0J-412D01*
G01Y829400D01*
G02X309300Y828988I-412J0D01*
G01X307900D01*
G37*
G36*
G01X283498Y685030D02*
Y682385D01*
G03X284802Y678695I5875J1D01*
G02X266379I-9211J-7446D01*
G03X267682Y682385I-4571J3689D01*
G01Y685030D01*
G02X283498I7908J0D01*
G37*
G36*
G01X310000Y397612D02*
G02X310412Y397200I0J-412D01*
G01Y395800D01*
G02X310000Y395388I-412J0D01*
G01X308600D01*
G02X308188Y395800I0J412D01*
G01Y397200D01*
G02X308600Y397612I412J0D01*
G01X310000D01*
G37*
G36*
G01X304400Y395388D02*
G02X303988Y395800I0J412D01*
G01Y397200D01*
G02X304400Y397612I412J0D01*
G01X305800D01*
G02X306212Y397200I0J-412D01*
G01Y395800D01*
G02X305800Y395388I-412J0D01*
G01X304400D01*
G37*
G36*
G01X305800Y401712D02*
G02X306212Y401300I0J-412D01*
G01Y399900D01*
G02X305800Y399488I-412J0D01*
G01X304400D01*
G02X303988Y399900I0J412D01*
G01Y401300D01*
G02X304400Y401712I412J0D01*
G01X305800D01*
G37*
G36*
G01X308600Y399488D02*
G02X308188Y399900I0J412D01*
G01Y401300D01*
G02X308600Y401712I412J0D01*
G01X310000D01*
G02X310412Y401300I0J-412D01*
G01Y399900D01*
G02X310000Y399488I-412J0D01*
G01X308600D01*
G37*
G36*
G01X283498Y279528D02*
Y276883D01*
G03X284802Y273193I5875J1D01*
G02X266379I-9211J-7446D01*
G03X267682Y276883I-4571J3689D01*
G01Y279528D01*
G02X283498I7908J0D01*
G37*
G36*
G01X188488Y1863749D02*
G02X192512I2012J0D01*
G01Y1860548D01*
G02X188488Y1860549I-2012J1D01*
G01Y1863749D01*
G37*
G36*
G01Y1458237D02*
G02X192512I2012J0D01*
G01Y1455036D01*
G02X188488Y1455037I-2012J1D01*
G01Y1458237D01*
G37*
G36*
G01Y1052725D02*
G02X192512I2012J0D01*
G01Y1049524D01*
G02X188488Y1049525I-2012J1D01*
G01Y1052725D01*
G37*
G36*
G01Y647213D02*
G02X192512I2012J0D01*
G01Y644012D01*
G02X188488Y644013I-2012J1D01*
G01Y647213D01*
G37*
G36*
G01Y241701D02*
G02X192512I2012J0D01*
G01Y238500D01*
G02X188488Y238501I-2012J1D01*
G01Y241701D01*
G37*
G36*
G01X158282Y1892664D02*
Y1885213D01*
X158281Y1885212D01*
X150380D01*
Y1892664D01*
X158282D01*
G37*
G36*
G01Y1902112D02*
Y1894661D01*
X158281Y1894660D01*
X150380D01*
Y1902112D01*
X158282D01*
G37*
G36*
G01X150380Y1904108D02*
Y1911560D01*
X150381Y1911562D01*
X158282D01*
Y1904108D01*
X150380D01*
G37*
G36*
G01X158282Y1921010D02*
Y1913559D01*
X158281Y1913558D01*
X150380D01*
Y1921010D01*
X158282D01*
G37*
G36*
G01Y1930460D02*
Y1923008D01*
X158281Y1923006D01*
X150380D01*
Y1930460D01*
X158282D01*
G37*
G36*
G01Y1939908D02*
Y1932457D01*
X158281Y1932456D01*
X150380D01*
Y1939908D01*
X158282D01*
G37*
G36*
G01X141106Y1925133D02*
G02X137084I-2011J0D01*
G01Y1928334D01*
G02X141106Y1928333I2011J-1D01*
G01Y1925133D01*
G37*
G36*
G01Y1906235D02*
G02X137084I-2011J0D01*
G01Y1909436D01*
G02X141106Y1909435I2011J-1D01*
G01Y1906235D01*
G37*
G36*
G01Y1887338D02*
G02X137084I-2011J0D01*
G01Y1890539D01*
G02X141106Y1890538I2011J-1D01*
G01Y1887338D01*
G37*
G36*
G01X147006Y1933982D02*
G02X142184I-2411J0D01*
G01Y1938383D01*
G02X147006Y1938382I2411J-1D01*
G01Y1933982D01*
G37*
G36*
G01X142184Y1919484D02*
G02X147006I2411J0D01*
G01Y1915083D01*
G02X142184Y1915084I-2411J1D01*
G01Y1919484D01*
G37*
G36*
G01X147006Y1896186D02*
G02X142184I-2411J0D01*
G01Y1900587D01*
G02X147006Y1900586I2411J-1D01*
G01Y1896186D01*
G37*
G36*
G01X158282Y1832822D02*
Y1825370D01*
X158281Y1825368D01*
X150380D01*
Y1832822D01*
X158282D01*
G37*
G36*
G01Y1842270D02*
Y1834819D01*
X158281Y1834818D01*
X150380D01*
Y1842270D01*
X158282D01*
G37*
G36*
G01Y1851718D02*
Y1844268D01*
X158281Y1844266D01*
X150380D01*
Y1851718D01*
X158282D01*
G37*
G36*
G01X170842Y1865892D02*
Y1858441D01*
X170840Y1858440D01*
X162938D01*
Y1865892D01*
X170842D01*
G37*
G36*
G01X176800Y1855430D02*
G02Y1859454I0J2012D01*
G01X180001D01*
G02X180000Y1855430I-1J-2012D01*
G01X176800D01*
G37*
G36*
G01X141106Y1836944D02*
G02X137084I-2011J0D01*
G01Y1840145D01*
G02X141106Y1840144I2011J-1D01*
G01Y1836944D01*
G37*
G36*
G01X147006Y1845793D02*
G02X142184I-2411J0D01*
G01Y1850194D01*
G02X147006Y1850193I2411J-1D01*
G01Y1845793D01*
G37*
G36*
G01X122988Y1753534D02*
G02X127012I2012J0D01*
G01Y1750333D01*
G02X122988Y1750334I-2012J1D01*
G01Y1753534D01*
G37*
G36*
G01X158282Y1515498D02*
Y1508047D01*
X158281Y1508046D01*
X150380D01*
Y1515498D01*
X158282D01*
G37*
G36*
G01Y1524948D02*
Y1517496D01*
X158281Y1517494D01*
X150380D01*
Y1524948D01*
X158282D01*
G37*
G36*
G01Y1534396D02*
Y1526945D01*
X158281Y1526944D01*
X150380D01*
Y1534396D01*
X158282D01*
G37*
G36*
G01X137084Y1522821D02*
G02X141106I2011J0D01*
G01Y1519620D01*
G02X137084Y1519621I-2011J1D01*
G01Y1522821D01*
G37*
G36*
G01X142184Y1513972D02*
G02X147006I2411J0D01*
G01Y1509571D01*
G02X142184Y1509572I-2411J1D01*
G01Y1513972D01*
G37*
G36*
G01Y1532870D02*
G02X147006I2411J0D01*
G01Y1528469D01*
G02X142184Y1528470I-2411J1D01*
G01Y1532870D01*
G37*
G36*
G01X158282Y1446206D02*
Y1438756D01*
X158281Y1438754D01*
X150380D01*
Y1446206D01*
X158282D01*
G37*
G36*
G01X170842Y1460380D02*
Y1452929D01*
X170840Y1452928D01*
X162938D01*
Y1460380D01*
X170842D01*
G37*
G36*
G01X158282Y1487152D02*
Y1479701D01*
X158281Y1479700D01*
X150380D01*
Y1487152D01*
X158282D01*
G37*
G36*
G01Y1496600D02*
Y1489149D01*
X158281Y1489148D01*
X150380D01*
Y1496600D01*
X158282D01*
G37*
G36*
G01Y1506050D02*
Y1498598D01*
X158281Y1498596D01*
X150380D01*
Y1506050D01*
X158282D01*
G37*
G36*
G01X180000Y1453942D02*
G02Y1449918I0J-2012D01*
G01X176799D01*
G02X176800Y1453942I1J2012D01*
G01X180000D01*
G37*
G36*
G01X137084Y1503923D02*
G02X141106I2011J0D01*
G01Y1500722D01*
G02X137084Y1500723I-2011J1D01*
G01Y1503923D01*
G37*
G36*
G01Y1485026D02*
G02X141106I2011J0D01*
G01Y1481825D01*
G02X137084Y1481826I-2011J1D01*
G01Y1485026D01*
G37*
G36*
G01X142184Y1495074D02*
G02X147006I2411J0D01*
G01Y1490673D01*
G02X142184Y1490674I-2411J1D01*
G01Y1495074D01*
G37*
G36*
G01Y1444681D02*
G02X147006I2411J0D01*
G01Y1440280D01*
G02X142184Y1440281I-2411J1D01*
G01Y1444681D01*
G37*
G36*
G01X158282Y1427310D02*
Y1419858D01*
X158281Y1419856D01*
X150380D01*
Y1427310D01*
X158282D01*
G37*
G36*
G01Y1436758D02*
Y1429307D01*
X158281Y1429306D01*
X150380D01*
Y1436758D01*
X158282D01*
G37*
G36*
G01X137084Y1434632D02*
G02X141106I2011J0D01*
G01Y1431431D01*
G02X137084Y1431432I-2011J1D01*
G01Y1434632D01*
G37*
G36*
G01X127488Y1348021D02*
G02X131512I2012J0D01*
G01Y1344820D01*
G02X127488Y1344821I-2012J1D01*
G01Y1348021D01*
G37*
G36*
G01X158282Y1081640D02*
Y1074189D01*
X158281Y1074188D01*
X150380D01*
Y1081640D01*
X158282D01*
G37*
G36*
G01Y1091088D02*
Y1083637D01*
X158281Y1083636D01*
X150380D01*
Y1091088D01*
X158282D01*
G37*
G36*
G01Y1100538D02*
Y1093086D01*
X158281Y1093084D01*
X150380D01*
Y1100538D01*
X158282D01*
G37*
G36*
G01Y1109986D02*
Y1102535D01*
X158281Y1102534D01*
X150380D01*
Y1109986D01*
X158282D01*
G37*
G36*
G01Y1119436D02*
Y1111984D01*
X158281Y1111982D01*
X150380D01*
Y1119436D01*
X158282D01*
G37*
G36*
G01Y1128884D02*
Y1121433D01*
X158281Y1121432D01*
X150380D01*
Y1128884D01*
X158282D01*
G37*
G36*
G01X137084Y1117309D02*
G02X141106I2011J0D01*
G01Y1114108D01*
G02X137084Y1114109I-2011J1D01*
G01Y1117309D01*
G37*
G36*
G01Y1098411D02*
G02X141106I2011J0D01*
G01Y1095210D01*
G02X137084Y1095211I-2011J1D01*
G01Y1098411D01*
G37*
G36*
G01Y1079514D02*
G02X141106I2011J0D01*
G01Y1076313D01*
G02X137084Y1076314I-2011J1D01*
G01Y1079514D01*
G37*
G36*
G01X142184Y1089562D02*
G02X147006I2411J0D01*
G01Y1085161D01*
G02X142184Y1085162I-2411J1D01*
G01Y1089562D01*
G37*
G36*
G01Y1108460D02*
G02X147006I2411J0D01*
G01Y1104059D01*
G02X142184Y1104060I-2411J1D01*
G01Y1108460D01*
G37*
G36*
G01Y1127358D02*
G02X147006I2411J0D01*
G01Y1122957D01*
G02X142184Y1122958I-2411J1D01*
G01Y1127358D01*
G37*
G36*
G01X158282Y1021798D02*
Y1014346D01*
X158281Y1014344D01*
X150380D01*
Y1021798D01*
X158282D01*
G37*
G36*
G01Y1031246D02*
Y1023795D01*
X158281Y1023794D01*
X150380D01*
Y1031246D01*
X158282D01*
G37*
G36*
G01X150380Y1033242D02*
Y1040693D01*
X150381Y1040694D01*
X158282D01*
Y1033242D01*
X150380D01*
G37*
G36*
G01X170842Y1054868D02*
Y1047417D01*
X170840Y1047416D01*
X162938D01*
Y1054868D01*
X170842D01*
G37*
G36*
G01X180000Y1048430D02*
G02Y1044406I0J-2012D01*
G01X176799D01*
G02X176800Y1048430I1J2012D01*
G01X180000D01*
G37*
G36*
G01X137084Y1029120D02*
G02X141106I2011J0D01*
G01Y1025919D01*
G02X137084Y1025920I-2011J1D01*
G01Y1029120D01*
G37*
G36*
G01X142184Y1039169D02*
G02X147006I2411J0D01*
G01Y1034768D01*
G02X142184Y1034769I-2411J1D01*
G01Y1039169D01*
G37*
G36*
G01X164988Y942509D02*
G02X169012I2012J0D01*
G01Y939308D01*
G02X164988Y939309I-2012J1D01*
G01Y942509D01*
G37*
G36*
G01X158282Y713924D02*
Y706472D01*
X158281Y706470D01*
X150380D01*
Y713924D01*
X158282D01*
G37*
G36*
G01Y723372D02*
Y715921D01*
X158281Y715920D01*
X150380D01*
Y723372D01*
X158282D01*
G37*
G36*
G01X137084Y711797D02*
G02X141106I2011J0D01*
G01Y708596D01*
G02X137084Y708597I-2011J1D01*
G01Y711797D01*
G37*
G36*
G01X142184Y721846D02*
G02X147006I2411J0D01*
G01Y717445D01*
G02X142184Y717446I-2411J1D01*
G01Y721846D01*
G37*
G36*
G01X170842Y649356D02*
Y641905D01*
X170840Y641904D01*
X162938D01*
Y649356D01*
X170842D01*
G37*
G36*
G01X158282Y676128D02*
Y668677D01*
X158281Y668676D01*
X150380D01*
Y676128D01*
X158282D01*
G37*
G36*
G01Y685576D02*
Y678125D01*
X158281Y678124D01*
X150380D01*
Y685576D01*
X158282D01*
G37*
G36*
G01Y695026D02*
Y687574D01*
X158281Y687572D01*
X150380D01*
Y695026D01*
X158282D01*
G37*
G36*
G01Y704474D02*
Y697023D01*
X158281Y697022D01*
X150380D01*
Y704474D01*
X158282D01*
G37*
G36*
G01X180000Y642918D02*
G02Y638894I0J-2012D01*
G01X176799D01*
G02X176800Y642918I1J2012D01*
G01X180000D01*
G37*
G36*
G01X137084Y692899D02*
G02X141106I2011J0D01*
G01Y689698D01*
G02X137084Y689699I-2011J1D01*
G01Y692899D01*
G37*
G36*
G01Y674002D02*
G02X141106I2011J0D01*
G01Y670801D01*
G02X137084Y670802I-2011J1D01*
G01Y674002D01*
G37*
G36*
G01X142184Y702948D02*
G02X147006I2411J0D01*
G01Y698547D01*
G02X142184Y698548I-2411J1D01*
G01Y702948D01*
G37*
G36*
G01Y684050D02*
G02X147006I2411J0D01*
G01Y679649D01*
G02X142184Y679650I-2411J1D01*
G01Y684050D01*
G37*
G36*
G01X158282Y616286D02*
Y608834D01*
X158281Y608832D01*
X150380D01*
Y616286D01*
X158282D01*
G37*
G36*
G01Y625734D02*
Y618283D01*
X158281Y618282D01*
X150380D01*
Y625734D01*
X158282D01*
G37*
G36*
G01Y635182D02*
Y627732D01*
X158281Y627730D01*
X150380D01*
Y635182D01*
X158282D01*
G37*
G36*
G01X137084Y623608D02*
G02X141106I2011J0D01*
G01Y620407D01*
G02X137084Y620408I-2011J1D01*
G01Y623608D01*
G37*
G36*
G01X142184Y633657D02*
G02X147006I2411J0D01*
G01Y629256D01*
G02X142184Y629257I-2411J1D01*
G01Y633657D01*
G37*
G36*
G01X121988Y537073D02*
G02X126012I2012J0D01*
G01Y533872D01*
G02X121988Y533873I-2012J1D01*
G01Y537073D01*
G37*
G36*
G01X158282Y280064D02*
Y272613D01*
X158281Y272612D01*
X150380D01*
Y280064D01*
X158282D01*
G37*
G36*
G01Y289514D02*
Y282062D01*
X158281Y282060D01*
X150380D01*
Y289514D01*
X158282D01*
G37*
G36*
G01Y298962D02*
Y291511D01*
X158281Y291510D01*
X150380D01*
Y298962D01*
X158282D01*
G37*
G36*
G01Y308412D02*
Y300960D01*
X158281Y300958D01*
X150380D01*
Y308412D01*
X158282D01*
G37*
G36*
G01Y317860D02*
Y310409D01*
X158281Y310408D01*
X150380D01*
Y317860D01*
X158282D01*
G37*
G36*
G01X137084Y306285D02*
G02X141106I2011J0D01*
G01Y303084D01*
G02X137084Y303085I-2011J1D01*
G01Y306285D01*
G37*
G36*
G01Y287387D02*
G02X141106I2011J0D01*
G01Y284186D01*
G02X137084Y284187I-2011J1D01*
G01Y287387D01*
G37*
G36*
G01X142184Y278538D02*
G02X147006I2411J0D01*
G01Y274137D01*
G02X142184Y274138I-2411J1D01*
G01Y278538D01*
G37*
G36*
G01Y297436D02*
G02X147006I2411J0D01*
G01Y293035D01*
G02X142184Y293036I-2411J1D01*
G01Y297436D01*
G37*
G36*
G01Y316334D02*
G02X147006I2411J0D01*
G01Y311933D01*
G02X142184Y311934I-2411J1D01*
G01Y316334D01*
G37*
G36*
G01X158282Y210774D02*
Y203322D01*
X158281Y203320D01*
X150380D01*
Y210774D01*
X158282D01*
G37*
G36*
G01Y220222D02*
Y212771D01*
X158281Y212770D01*
X150380D01*
Y220222D01*
X158282D01*
G37*
G36*
G01Y229670D02*
Y222220D01*
X158281Y222218D01*
X150380D01*
Y229670D01*
X158282D01*
G37*
G36*
G01X170842Y243844D02*
Y236393D01*
X170840Y236392D01*
X162938D01*
Y243844D01*
X170842D01*
G37*
G36*
G01X158282Y270616D02*
Y263165D01*
X158281Y263164D01*
X150380D01*
Y270616D01*
X158282D01*
G37*
G36*
G01X180000Y237406D02*
G02Y233382I0J-2012D01*
G01X176799D01*
G02X176800Y237406I1J2012D01*
G01X180000D01*
G37*
G36*
G01X137084Y268490D02*
G02X141106I2011J0D01*
G01Y265289D01*
G02X137084Y265290I-2011J1D01*
G01Y268490D01*
G37*
G36*
G01Y218096D02*
G02X141106I2011J0D01*
G01Y214895D01*
G02X137084Y214896I-2011J1D01*
G01Y218096D01*
G37*
G36*
G01X142184Y228145D02*
G02X147006I2411J0D01*
G01Y223744D01*
G02X142184Y223745I-2411J1D01*
G01Y228145D01*
G37*
G36*
G01X121988Y131559D02*
G02X126012I2012J0D01*
G01Y128358D01*
G02X121988Y128359I-2012J1D01*
G01Y131559D01*
G37*
G36*
G01X97088Y1768381D02*
G02X101912I2412J0D01*
G01Y1763980D01*
G02X97088Y1763981I-2412J1D01*
G01Y1768381D01*
G37*
G36*
G01X85812Y1781352D02*
Y1788804D01*
X85814Y1788806D01*
X93716D01*
Y1781352D01*
X85812D01*
G37*
G36*
G01Y1771904D02*
Y1779355D01*
X85814Y1779356D01*
X93716D01*
Y1771904D01*
X85812D01*
G37*
G36*
G01Y1762456D02*
Y1769906D01*
X85814Y1769908D01*
X93716D01*
Y1762456D01*
X85812D01*
G37*
G36*
G01X73254Y1748282D02*
Y1755733D01*
X73255Y1755734D01*
X81156D01*
Y1748282D01*
X73254D01*
G37*
G36*
G01X85812Y1721510D02*
Y1728961D01*
X85814Y1728962D01*
X93716D01*
Y1721510D01*
X85812D01*
G37*
G36*
G01X102988Y1726836D02*
G02X107012I2012J0D01*
G01Y1723635D01*
G02X102988Y1723636I-2012J1D01*
G01Y1726836D01*
G37*
G36*
G01Y1777230D02*
G02X107012I2012J0D01*
G01Y1774029D01*
G02X102988Y1774030I-2012J1D01*
G01Y1777230D01*
G37*
G36*
G01X70012Y1750407D02*
G02X65988I-2012J0D01*
G01Y1753608D01*
G02X70012Y1753607I2012J-1D01*
G01Y1750407D01*
G37*
G36*
G01X53670Y1679148D02*
G02X54072Y1679550I402J0D01*
G01X59172D01*
G02X59574Y1679148I0J-402D01*
G01Y1673948D01*
G02X59172Y1673546I-402J0D01*
G01X54072D01*
G02X53670Y1673948I0J402D01*
G01Y1679148D01*
G37*
G36*
G01X97088Y1699090D02*
G02X101912I2412J0D01*
G01Y1694689D01*
G02X97088Y1694690I-2412J1D01*
G01Y1699090D01*
G37*
G36*
G01X85812Y1674266D02*
Y1681717D01*
X85814Y1681718D01*
X93716D01*
Y1674266D01*
X85812D01*
G37*
G36*
G01Y1683714D02*
Y1691166D01*
X85814Y1691168D01*
X93716D01*
Y1683714D01*
X85812D01*
G37*
G36*
G01X97088Y1680192D02*
G02X101912I2412J0D01*
G01Y1675791D01*
G02X97088Y1675792I-2412J1D01*
G01Y1680192D01*
G37*
G36*
G01X85812Y1712062D02*
Y1719513D01*
X85814Y1719514D01*
X93716D01*
Y1712062D01*
X85812D01*
G37*
G36*
G01Y1702612D02*
Y1710064D01*
X85814Y1710066D01*
X93716D01*
Y1702612D01*
X85812D01*
G37*
G36*
G01Y1693164D02*
Y1700615D01*
X85814Y1700616D01*
X93716D01*
Y1693164D01*
X85812D01*
G37*
G36*
G01X102988Y1707939D02*
G02X107012I2012J0D01*
G01Y1704738D01*
G02X102988Y1704739I-2012J1D01*
G01Y1707939D01*
G37*
G36*
G01Y1689041D02*
G02X107012I2012J0D01*
G01Y1685840D01*
G02X102988Y1685841I-2012J1D01*
G01Y1689041D01*
G37*
G36*
G01X97088Y1717988D02*
G02X101912I2412J0D01*
G01Y1713587D01*
G02X97088Y1713588I-2412J1D01*
G01Y1717988D01*
G37*
G36*
G01X85812Y1356942D02*
Y1364394D01*
X85814Y1364396D01*
X93716D01*
Y1356942D01*
X85812D01*
G37*
G36*
G01Y1366392D02*
Y1373843D01*
X85814Y1373844D01*
X93716D01*
Y1366392D01*
X85812D01*
G37*
G36*
G01Y1375840D02*
Y1383292D01*
X85814Y1383294D01*
X93716D01*
Y1375840D01*
X85812D01*
G37*
G36*
G01X107012Y1368518D02*
G02X102988I-2012J0D01*
G01Y1371719D01*
G02X107012Y1371718I2012J-1D01*
G01Y1368518D01*
G37*
G36*
G01X101912Y1289178D02*
G02X97088I-2412J0D01*
G01Y1293579D01*
G02X101912Y1293578I2412J-1D01*
G01Y1289178D01*
G37*
G36*
G01X97088Y1362869D02*
G02X101912I2412J0D01*
G01Y1358468D01*
G02X97088Y1358469I-2412J1D01*
G01Y1362869D01*
G37*
G36*
G01X101912Y1308076D02*
G02X97088I-2412J0D01*
G01Y1312477D01*
G02X101912Y1312476I2412J-1D01*
G01Y1308076D01*
G37*
G36*
G01X73254Y1342770D02*
Y1350221D01*
X73255Y1350222D01*
X81156D01*
Y1342770D01*
X73254D01*
G37*
G36*
G01X85812Y1315998D02*
Y1323449D01*
X85814Y1323450D01*
X93716D01*
Y1315998D01*
X85812D01*
G37*
G36*
G01Y1306550D02*
Y1314001D01*
X85814Y1314002D01*
X93716D01*
Y1306550D01*
X85812D01*
G37*
G36*
G01Y1297100D02*
Y1304552D01*
X85814Y1304554D01*
X93716D01*
Y1297100D01*
X85812D01*
G37*
G36*
G01Y1287652D02*
Y1295103D01*
X85814Y1295104D01*
X93716D01*
Y1287652D01*
X85812D01*
G37*
G36*
G01X70012Y1344895D02*
G02X65988I-2012J0D01*
G01Y1348096D01*
G02X70012Y1348095I2012J-1D01*
G01Y1344895D01*
G37*
G36*
G01X107012Y1318124D02*
G02X102988I-2012J0D01*
G01Y1321325D01*
G02X107012Y1321324I2012J-1D01*
G01Y1318124D01*
G37*
G36*
G01Y1299227D02*
G02X102988I-2012J0D01*
G01Y1302428D01*
G02X107012Y1302427I2012J-1D01*
G01Y1299227D01*
G37*
G36*
G01X101912Y1270280D02*
G02X97088I-2412J0D01*
G01Y1274681D01*
G02X101912Y1274680I2412J-1D01*
G01Y1270280D01*
G37*
G36*
G01X85812Y1278202D02*
Y1285654D01*
X85814Y1285656D01*
X93716D01*
Y1278202D01*
X85812D01*
G37*
G36*
G01Y1268754D02*
Y1276205D01*
X85814Y1276206D01*
X93716D01*
Y1268754D01*
X85812D01*
G37*
G36*
G01X107012Y1280329D02*
G02X102988I-2012J0D01*
G01Y1283530D01*
G02X107012Y1283529I2012J-1D01*
G01Y1280329D01*
G37*
G36*
G01X85812Y970328D02*
Y977780D01*
X85814Y977782D01*
X93716D01*
Y970328D01*
X85812D01*
G37*
G36*
G01Y960880D02*
Y968331D01*
X85814Y968332D01*
X93716D01*
Y960880D01*
X85812D01*
G37*
G36*
G01Y951432D02*
Y958882D01*
X85814Y958884D01*
X93716D01*
Y951432D01*
X85812D01*
G37*
G36*
G01X73254Y937258D02*
Y944709D01*
X73255Y944710D01*
X81156D01*
Y937258D01*
X73254D01*
G37*
G36*
G01X70012Y939383D02*
G02X65988I-2012J0D01*
G01Y942584D01*
G02X70012Y942583I2012J-1D01*
G01Y939383D01*
G37*
G36*
G01X107012Y963006D02*
G02X102988I-2012J0D01*
G01Y966207D01*
G02X107012Y966206I2012J-1D01*
G01Y963006D01*
G37*
G36*
G01X101912Y952957D02*
G02X97088I-2412J0D01*
G01Y957358D01*
G02X101912Y957357I2412J-1D01*
G01Y952957D01*
G37*
G36*
G01X85812Y863242D02*
Y870693D01*
X85814Y870694D01*
X93716D01*
Y863242D01*
X85812D01*
G37*
G36*
G01Y872690D02*
Y880142D01*
X85814Y880144D01*
X93716D01*
Y872690D01*
X85812D01*
G37*
G36*
G01X97088Y869168D02*
G02X101912I2412J0D01*
G01Y864767D01*
G02X97088Y864768I-2412J1D01*
G01Y869168D01*
G37*
G36*
G01X85812Y910486D02*
Y917937D01*
X85814Y917938D01*
X93716D01*
Y910486D01*
X85812D01*
G37*
G36*
G01Y901038D02*
Y908489D01*
X85814Y908490D01*
X93716D01*
Y901038D01*
X85812D01*
G37*
G36*
G01Y891588D02*
Y899040D01*
X85814Y899042D01*
X93716D01*
Y891588D01*
X85812D01*
G37*
G36*
G01Y882140D02*
Y889591D01*
X85814Y889592D01*
X93716D01*
Y882140D01*
X85812D01*
G37*
G36*
G01X107012Y912612D02*
G02X102988I-2012J0D01*
G01Y915813D01*
G02X107012Y915812I2012J-1D01*
G01Y912612D01*
G37*
G36*
G01Y893715D02*
G02X102988I-2012J0D01*
G01Y896916D01*
G02X107012Y896915I2012J-1D01*
G01Y893715D01*
G37*
G36*
G01Y874817D02*
G02X102988I-2012J0D01*
G01Y878018D01*
G02X107012Y878017I2012J-1D01*
G01Y874817D01*
G37*
G36*
G01X101912Y902564D02*
G02X97088I-2412J0D01*
G01Y906965D01*
G02X101912Y906964I2412J-1D01*
G01Y902564D01*
G37*
G36*
G01Y883666D02*
G02X97088I-2412J0D01*
G01Y888067D01*
G02X101912Y888066I2412J-1D01*
G01Y883666D01*
G37*
G36*
G01X85812Y564816D02*
Y572268D01*
X85814Y572270D01*
X93716D01*
Y564816D01*
X85812D01*
G37*
G36*
G01X97088Y551845D02*
G02X101912I2412J0D01*
G01Y547444D01*
G02X97088Y547445I-2412J1D01*
G01Y551845D01*
G37*
G36*
G01X85812Y545918D02*
Y553370D01*
X85814Y553372D01*
X93716D01*
Y545918D01*
X85812D01*
G37*
G36*
G01Y555368D02*
Y562819D01*
X85814Y562820D01*
X93716D01*
Y555368D01*
X85812D01*
G37*
G36*
G01X73254Y531746D02*
Y539197D01*
X73255Y539198D01*
X81156D01*
Y531746D01*
X73254D01*
G37*
G36*
G01X85812Y504974D02*
Y512425D01*
X85814Y512426D01*
X93716D01*
Y504974D01*
X85812D01*
G37*
G36*
G01Y495526D02*
Y502977D01*
X85814Y502978D01*
X93716D01*
Y495526D01*
X85812D01*
G37*
G36*
G01Y486076D02*
Y493528D01*
X85814Y493530D01*
X93716D01*
Y486076D01*
X85812D01*
G37*
G36*
G01X70012Y533871D02*
G02X65988I-2012J0D01*
G01Y537072D01*
G02X70012Y537071I2012J-1D01*
G01Y533871D01*
G37*
G36*
G01X107012Y507100D02*
G02X102988I-2012J0D01*
G01Y510301D01*
G02X107012Y510300I2012J-1D01*
G01Y507100D01*
G37*
G36*
G01Y557494D02*
G02X102988I-2012J0D01*
G01Y560695D01*
G02X107012Y560694I2012J-1D01*
G01Y557494D01*
G37*
G36*
G01Y488203D02*
G02X102988I-2012J0D01*
G01Y491404D01*
G02X107012Y491403I2012J-1D01*
G01Y488203D01*
G37*
G36*
G01X101912Y497052D02*
G02X97088I-2412J0D01*
G01Y501453D01*
G02X101912Y501452I2412J-1D01*
G01Y497052D01*
G37*
G36*
G01X85812Y476628D02*
Y484079D01*
X85814Y484080D01*
X93716D01*
Y476628D01*
X85812D01*
G37*
G36*
G01Y467178D02*
Y474630D01*
X85814Y474632D01*
X93716D01*
Y467178D01*
X85812D01*
G37*
G36*
G01Y457730D02*
Y465181D01*
X85814Y465182D01*
X93716D01*
Y457730D01*
X85812D01*
G37*
G36*
G01X107012Y469305D02*
G02X102988I-2012J0D01*
G01Y472506D01*
G02X107012Y472505I2012J-1D01*
G01Y469305D01*
G37*
G36*
G01X97088Y463656D02*
G02X101912I2412J0D01*
G01Y459255D01*
G02X97088Y459256I-2412J1D01*
G01Y463656D01*
G37*
G36*
G01X101912Y478154D02*
G02X97088I-2412J0D01*
G01Y482555D01*
G02X101912Y482554I2412J-1D01*
G01Y478154D01*
G37*
G36*
G01X85812Y159304D02*
Y166756D01*
X85814Y166758D01*
X93716D01*
Y159304D01*
X85812D01*
G37*
G36*
G01Y149856D02*
Y157307D01*
X85814Y157308D01*
X93716D01*
Y149856D01*
X85812D01*
G37*
G36*
G01Y140408D02*
Y147858D01*
X85814Y147860D01*
X93716D01*
Y140408D01*
X85812D01*
G37*
G36*
G01X73254Y126234D02*
Y133685D01*
X73255Y133686D01*
X81156D01*
Y126234D01*
X73254D01*
G37*
G36*
G01X65988Y131559D02*
G02X70012I2012J0D01*
G01Y128358D01*
G02X65988Y128359I-2012J1D01*
G01Y131559D01*
G37*
G36*
G01X107012Y151982D02*
G02X102988I-2012J0D01*
G01Y155183D01*
G02X107012Y155182I2012J-1D01*
G01Y151982D01*
G37*
G36*
G01X101912Y141933D02*
G02X97088I-2412J0D01*
G01Y146334D01*
G02X101912Y146333I2412J-1D01*
G01Y141933D01*
G37*
G36*
G01Y72642D02*
G02X97088I-2412J0D01*
G01Y77043D01*
G02X101912Y77042I2412J-1D01*
G01Y72642D01*
G37*
G36*
G01X97088Y58244D02*
G02X101912I2412J0D01*
G01Y53843D01*
G02X97088Y53844I-2412J1D01*
G01Y58244D01*
G37*
G36*
G01X85812Y99462D02*
Y106913D01*
X85814Y106914D01*
X93716D01*
Y99462D01*
X85812D01*
G37*
G36*
G01Y90014D02*
Y97465D01*
X85814Y97466D01*
X93716D01*
Y90014D01*
X85812D01*
G37*
G36*
G01Y80564D02*
Y88016D01*
X85814Y88018D01*
X93716D01*
Y80564D01*
X85812D01*
G37*
G36*
G01Y71116D02*
Y78567D01*
X85814Y78568D01*
X93716D01*
Y71116D01*
X85812D01*
G37*
G36*
G01Y61666D02*
Y69118D01*
X85814Y69120D01*
X93716D01*
Y61666D01*
X85812D01*
G37*
G36*
G01Y52218D02*
Y59669D01*
X85814Y59670D01*
X93716D01*
Y52218D01*
X85812D01*
G37*
G36*
G01X107012Y101588D02*
G02X102988I-2012J0D01*
G01Y104789D01*
G02X107012Y104788I2012J-1D01*
G01Y101588D01*
G37*
G36*
G01Y82691D02*
G02X102988I-2012J0D01*
G01Y85892D01*
G02X107012Y85891I2012J-1D01*
G01Y82691D01*
G37*
G36*
G01Y63793D02*
G02X102988I-2012J0D01*
G01Y66994D01*
G02X107012Y66993I2012J-1D01*
G01Y63793D01*
G37*
G36*
G01X101912Y91540D02*
G02X97088I-2412J0D01*
G01Y95941D01*
G02X101912Y95940I2412J-1D01*
G01Y91540D01*
G37*
G36*
G01X29562Y1922835D02*
Y1920190D01*
G03X30865Y1916500I5874J-1D01*
G02X12442I-9211J-7446D01*
G03X13746Y1920190I-4571J3691D01*
G01Y1922835D01*
G02X29562I7908J0D01*
G37*
G36*
G01X28600Y1774148D02*
G02X28198Y1774550I0J402D01*
G01Y1779650D01*
G02X28600Y1780052I402J0D01*
G01X33800D01*
G02X34202Y1779650I0J-402D01*
G01Y1774550D01*
G02X33800Y1774148I-402J0D01*
G01X28600D01*
G37*
G36*
G01X28700Y1771570D02*
G02Y1767546I0J-2012D01*
G01X25499D01*
G02X25500Y1771570I1J2012D01*
G01X28700D01*
G37*
G36*
G01X29540Y1732221D02*
G02X25518I-2011J0D01*
G01Y1735422D01*
G02X29540Y1735421I2011J-1D01*
G01Y1732221D01*
G37*
G36*
G01Y1744820D02*
G02X25518I-2011J0D01*
G01Y1748021D01*
G02X29540Y1748020I2011J-1D01*
G01Y1744820D01*
G37*
G36*
G01Y1757418D02*
G02X25518I-2011J0D01*
G01Y1760619D01*
G02X29540Y1760618I2011J-1D01*
G01Y1757418D01*
G37*
G36*
G01X22012Y1725729D02*
G02X17988I-2012J0D01*
G01Y1728930D01*
G02X22012Y1728929I2012J-1D01*
G01Y1725729D01*
G37*
G36*
G01Y1738328D02*
G02X17988I-2012J0D01*
G01Y1741529D01*
G02X22012Y1741528I2012J-1D01*
G01Y1738328D01*
G37*
G36*
G01Y1750926D02*
G02X17988I-2012J0D01*
G01Y1754127D01*
G02X22012Y1754126I2012J-1D01*
G01Y1750926D01*
G37*
G36*
G01X25518Y1688177D02*
G02X29540I2011J0D01*
G01Y1684976D01*
G02X25518Y1684977I-2011J1D01*
G01Y1688177D01*
G37*
G36*
G01Y1700776D02*
G02X29540I2011J0D01*
G01Y1697575D01*
G02X25518Y1697576I-2011J1D01*
G01Y1700776D01*
G37*
G36*
G01Y1675579D02*
G02X29540I2011J0D01*
G01Y1672378D01*
G02X25518Y1672379I-2011J1D01*
G01Y1675579D01*
G37*
G36*
G01X29540Y1719623D02*
G02X25518I-2011J0D01*
G01Y1722824D01*
G02X29540Y1722823I2011J-1D01*
G01Y1719623D01*
G37*
G36*
G01X17988Y1669087D02*
G02X22012I2012J0D01*
G01Y1665886D01*
G02X17988Y1665887I-2012J1D01*
G01Y1669087D01*
G37*
G36*
G01Y1681685D02*
G02X22012I2012J0D01*
G01Y1678484D01*
G02X17988Y1678485I-2012J1D01*
G01Y1681685D01*
G37*
G36*
G01Y1694283D02*
G02X22012I2012J0D01*
G01Y1691082D01*
G02X17988Y1691083I-2012J1D01*
G01Y1694283D01*
G37*
G36*
G01X22012Y1713131D02*
G02X17988I-2012J0D01*
G01Y1716332D01*
G02X22012Y1716331I2012J-1D01*
G01Y1713131D01*
G37*
G36*
G01X29540Y1583999D02*
G02X25518I-2011J0D01*
G01Y1587200D01*
G02X29540Y1587199I2011J-1D01*
G01Y1583999D01*
G37*
G36*
G01Y1596597D02*
G02X25518I-2011J0D01*
G01Y1599798D01*
G02X29540Y1599797I2011J-1D01*
G01Y1596597D01*
G37*
G36*
G01Y1609196D02*
G02X25518I-2011J0D01*
G01Y1612397D01*
G02X29540Y1612396I2011J-1D01*
G01Y1609196D01*
G37*
G36*
G01Y1621794D02*
G02X25518I-2011J0D01*
G01Y1624995D01*
G02X29540Y1624994I2011J-1D01*
G01Y1621794D01*
G37*
G36*
G01X25518Y1637593D02*
G02X29540I2011J0D01*
G01Y1634392D01*
G02X25518Y1634393I-2011J1D01*
G01Y1637593D01*
G37*
G36*
G01X22012Y1590296D02*
G02X17988I-2012J0D01*
G01Y1593497D01*
G02X22012Y1593496I2012J-1D01*
G01Y1590296D01*
G37*
G36*
G01Y1602894D02*
G02X17988I-2012J0D01*
G01Y1606095D01*
G02X22012Y1606094I2012J-1D01*
G01Y1602894D01*
G37*
G36*
G01Y1615493D02*
G02X17988I-2012J0D01*
G01Y1618694D01*
G02X22012Y1618693I2012J-1D01*
G01Y1615493D01*
G37*
G36*
G01Y1628091D02*
G02X17988I-2012J0D01*
G01Y1631292D01*
G02X22012Y1631291I2012J-1D01*
G01Y1628091D01*
G37*
G36*
G01X17988Y1643890D02*
G02X22012I2012J0D01*
G01Y1640689D01*
G02X17988Y1640690I-2012J1D01*
G01Y1643890D01*
G37*
G36*
G01X32050Y1509198D02*
G02X31648Y1509600I0J402D01*
G01Y1514800D01*
G02X32050Y1515202I402J0D01*
G01X37150D01*
G02X37552Y1514800I0J-402D01*
G01Y1509600D01*
G02X37150Y1509198I-402J0D01*
G01X32050D01*
G37*
G36*
G01X33001Y1516112D02*
G02Y1520134I0J2011D01*
G01X36202D01*
G02X36201Y1516112I-1J-2011D01*
G01X33001D01*
G37*
G36*
G01X25518Y1527356D02*
G02X29540I2011J0D01*
G01Y1524155D01*
G02X25518Y1524156I-2011J1D01*
G01Y1527356D01*
G37*
G36*
G01Y1539955D02*
G02X29540I2011J0D01*
G01Y1536754D01*
G02X25518Y1536755I-2011J1D01*
G01Y1539955D01*
G37*
G36*
G01Y1552553D02*
G02X29540I2011J0D01*
G01Y1549352D01*
G02X25518Y1549353I-2011J1D01*
G01Y1552553D01*
G37*
G36*
G01Y1565152D02*
G02X29540I2011J0D01*
G01Y1561951D01*
G02X25518Y1561952I-2011J1D01*
G01Y1565152D01*
G37*
G36*
G01X17988Y1533654D02*
G02X22012I2012J0D01*
G01Y1530453D01*
G02X17988Y1530454I-2012J1D01*
G01Y1533654D01*
G37*
G36*
G01Y1546252D02*
G02X22012I2012J0D01*
G01Y1543051D01*
G02X17988Y1543052I-2012J1D01*
G01Y1546252D01*
G37*
G36*
G01Y1558850D02*
G02X22012I2012J0D01*
G01Y1555649D01*
G02X17988Y1555650I-2012J1D01*
G01Y1558850D01*
G37*
G36*
G01Y1571449D02*
G02X22012I2012J0D01*
G01Y1568248D01*
G02X17988Y1568249I-2012J1D01*
G01Y1571449D01*
G37*
G36*
G01X25800Y1487098D02*
G02X25398Y1487500I0J402D01*
G01Y1492700D01*
G02X25800Y1493102I402J0D01*
G01X31000D01*
G02X31402Y1492700I0J-402D01*
G01Y1487500D01*
G02X31000Y1487098I-402J0D01*
G01X25800D01*
G37*
G36*
G01X29540Y1365102D02*
G02X25518I-2011J0D01*
G01Y1368303D01*
G02X29540Y1368302I2011J-1D01*
G01Y1365102D01*
G37*
G36*
G01Y1377700D02*
G02X25518I-2011J0D01*
G01Y1380901D01*
G02X29540Y1380900I2011J-1D01*
G01Y1377700D01*
G37*
G36*
G01X25518Y1393499D02*
G02X29540I2011J0D01*
G01Y1390298D01*
G02X25518Y1390299I-2011J1D01*
G01Y1393499D01*
G37*
G36*
G01X29540Y1402897D02*
G02X25518I-2011J0D01*
G01Y1406098D01*
G02X29540Y1406097I2011J-1D01*
G01Y1402897D01*
G37*
G36*
G01X17988Y1374599D02*
G02X22012I2012J0D01*
G01Y1371398D01*
G02X17988Y1371399I-2012J1D01*
G01Y1374599D01*
G37*
G36*
G01Y1387198D02*
G02X22012I2012J0D01*
G01Y1383997D01*
G02X17988Y1383998I-2012J1D01*
G01Y1387198D01*
G37*
G36*
G01Y1399796D02*
G02X22012I2012J0D01*
G01Y1396595D01*
G02X17988Y1396596I-2012J1D01*
G01Y1399796D01*
G37*
G36*
G01Y1412395D02*
G02X22012I2012J0D01*
G01Y1409194D01*
G02X17988Y1409195I-2012J1D01*
G01Y1412395D01*
G37*
G36*
G01X29540Y1292661D02*
G02X25518I-2011J0D01*
G01Y1295862D01*
G02X29540Y1295861I2011J-1D01*
G01Y1292661D01*
G37*
G36*
G01X25518Y1318108D02*
G02X29540I2011J0D01*
G01Y1314907D01*
G02X25518Y1314908I-2011J1D01*
G01Y1318108D01*
G37*
G36*
G01Y1330707D02*
G02X29540I2011J0D01*
G01Y1327506D01*
G02X25518Y1327507I-2011J1D01*
G01Y1330707D01*
G37*
G36*
G01Y1343305D02*
G02X29540I2011J0D01*
G01Y1340104D01*
G02X25518Y1340105I-2011J1D01*
G01Y1343305D01*
G37*
G36*
G01Y1355904D02*
G02X29540I2011J0D01*
G01Y1352703D01*
G02X25518Y1352704I-2011J1D01*
G01Y1355904D01*
G37*
G36*
G01X17988Y1362001D02*
G02X22012I2012J0D01*
G01Y1358800D01*
G02X17988Y1358801I-2012J1D01*
G01Y1362001D01*
G37*
G36*
G01Y1349402D02*
G02X22012I2012J0D01*
G01Y1346201D01*
G02X17988Y1346202I-2012J1D01*
G01Y1349402D01*
G37*
G36*
G01Y1336804D02*
G02X22012I2012J0D01*
G01Y1333603D01*
G02X17988Y1333604I-2012J1D01*
G01Y1336804D01*
G37*
G36*
G01Y1324206D02*
G02X22012I2012J0D01*
G01Y1321005D01*
G02X17988Y1321006I-2012J1D01*
G01Y1324206D01*
G37*
G36*
G01Y1302158D02*
G02X22012I2012J0D01*
G01Y1298957D01*
G02X17988Y1298958I-2012J1D01*
G01Y1302158D01*
G37*
G36*
G01Y1289560D02*
G02X22012I2012J0D01*
G01Y1286359D01*
G02X17988Y1286360I-2012J1D01*
G01Y1289560D01*
G37*
G36*
G01X29540Y1280063D02*
G02X25518I-2011J0D01*
G01Y1283264D01*
G02X29540Y1283263I2011J-1D01*
G01Y1280063D01*
G37*
G36*
G01Y1267464D02*
G02X25518I-2011J0D01*
G01Y1270665D01*
G02X29540Y1270664I2011J-1D01*
G01Y1267464D01*
G37*
G36*
G01Y1254866D02*
G02X25518I-2011J0D01*
G01Y1258067D01*
G02X29540Y1258066I2011J-1D01*
G01Y1254866D01*
G37*
G36*
G01Y1223370D02*
G02X25518I-2011J0D01*
G01Y1226571D01*
G02X29540Y1226570I2011J-1D01*
G01Y1223370D01*
G37*
G36*
G01X17988Y1276961D02*
G02X22012I2012J0D01*
G01Y1273760D01*
G02X17988Y1273761I-2012J1D01*
G01Y1276961D01*
G37*
G36*
G01Y1264363D02*
G02X22012I2012J0D01*
G01Y1261162D01*
G02X17988Y1261163I-2012J1D01*
G01Y1264363D01*
G37*
G36*
G01Y1251765D02*
G02X22012I2012J0D01*
G01Y1248564D01*
G02X17988Y1248565I-2012J1D01*
G01Y1251765D01*
G37*
G36*
G01Y1220269D02*
G02X22012I2012J0D01*
G01Y1217068D01*
G02X17988Y1217069I-2012J1D01*
G01Y1220269D01*
G37*
G36*
G01X29540Y1210771D02*
G02X25518I-2011J0D01*
G01Y1213972D01*
G02X29540Y1213971I2011J-1D01*
G01Y1210771D01*
G37*
G36*
G01Y1198173D02*
G02X25518I-2011J0D01*
G01Y1201374D01*
G02X29540Y1201373I2011J-1D01*
G01Y1198173D01*
G37*
G36*
G01Y1185574D02*
G02X25518I-2011J0D01*
G01Y1188775D01*
G02X29540Y1188774I2011J-1D01*
G01Y1185574D01*
G37*
G36*
G01Y1172976D02*
G02X25518I-2011J0D01*
G01Y1176177D01*
G02X29540Y1176176I2011J-1D01*
G01Y1172976D01*
G37*
G36*
G01Y1160378D02*
G02X25518I-2011J0D01*
G01Y1163579D01*
G02X29540Y1163578I2011J-1D01*
G01Y1160378D01*
G37*
G36*
G01Y1147779D02*
G02X25518I-2011J0D01*
G01Y1150980D01*
G02X29540Y1150979I2011J-1D01*
G01Y1147779D01*
G37*
G36*
G01X17988Y1195072D02*
G02X22012I2012J0D01*
G01Y1191871D01*
G02X17988Y1191872I-2012J1D01*
G01Y1195072D01*
G37*
G36*
G01Y1207670D02*
G02X22012I2012J0D01*
G01Y1204469D01*
G02X17988Y1204470I-2012J1D01*
G01Y1207670D01*
G37*
G36*
G01Y1182473D02*
G02X22012I2012J0D01*
G01Y1179272D01*
G02X17988Y1179273I-2012J1D01*
G01Y1182473D01*
G37*
G36*
G01Y1169875D02*
G02X22012I2012J0D01*
G01Y1166674D01*
G02X17988Y1166675I-2012J1D01*
G01Y1169875D01*
G37*
G36*
G01Y1157276D02*
G02X22012I2012J0D01*
G01Y1154075D01*
G02X17988Y1154076I-2012J1D01*
G01Y1157276D01*
G37*
G36*
G01Y1144678D02*
G02X22012I2012J0D01*
G01Y1141477D01*
G02X17988Y1141478I-2012J1D01*
G01Y1144678D01*
G37*
G36*
G01X25518Y1113384D02*
G02X29540I2011J0D01*
G01Y1110183D01*
G02X25518Y1110184I-2011J1D01*
G01Y1113384D01*
G37*
G36*
G01Y1138381D02*
G02X29540I2011J0D01*
G01Y1135180D01*
G02X25518Y1135181I-2011J1D01*
G01Y1138381D01*
G37*
G36*
G01Y1100785D02*
G02X29540I2011J0D01*
G01Y1097584D01*
G02X25518Y1097585I-2011J1D01*
G01Y1100785D01*
G37*
G36*
G01X17988Y1119481D02*
G02X22012I2012J0D01*
G01Y1116280D01*
G02X17988Y1116281I-2012J1D01*
G01Y1119481D01*
G37*
G36*
G01Y1106883D02*
G02X22012I2012J0D01*
G01Y1103682D01*
G02X17988Y1103683I-2012J1D01*
G01Y1106883D01*
G37*
G36*
G01X25518Y859441D02*
G02X29540I2011J0D01*
G01Y856240D01*
G02X25518Y856241I-2011J1D01*
G01Y859441D01*
G37*
G36*
G01X29540Y868839D02*
G02X25518I-2011J0D01*
G01Y872040D01*
G02X29540Y872039I2011J-1D01*
G01Y868839D01*
G37*
G36*
G01X25518Y884687D02*
G02X29540I2011J0D01*
G01Y881486D01*
G02X25518Y881487I-2011J1D01*
G01Y884687D01*
G37*
G36*
G01Y910034D02*
G02X29540I2011J0D01*
G01Y906833D01*
G02X25518Y906834I-2011J1D01*
G01Y910034D01*
G37*
G36*
G01Y897436D02*
G02X29540I2011J0D01*
G01Y894235D01*
G02X25518Y894236I-2011J1D01*
G01Y897436D01*
G37*
G36*
G01X17988Y853339D02*
G02X22012I2012J0D01*
G01Y850138D01*
G02X17988Y850139I-2012J1D01*
G01Y853339D01*
G37*
G36*
G01Y865938D02*
G02X22012I2012J0D01*
G01Y862737D01*
G02X17988Y862738I-2012J1D01*
G01Y865938D01*
G37*
G36*
G01Y878536D02*
G02X22012I2012J0D01*
G01Y875335D01*
G02X17988Y875336I-2012J1D01*
G01Y878536D01*
G37*
G36*
G01Y903733D02*
G02X22012I2012J0D01*
G01Y900532D01*
G02X17988Y900533I-2012J1D01*
G01Y903733D01*
G37*
G36*
G01Y916332D02*
G02X22012I2012J0D01*
G01Y913131D01*
G02X17988Y913132I-2012J1D01*
G01Y916332D01*
G37*
G36*
G01X25518Y846842D02*
G02X29540I2011J0D01*
G01Y843641D01*
G02X25518Y843642I-2011J1D01*
G01Y846842D01*
G37*
G36*
G01Y834444D02*
G02X29540I2011J0D01*
G01Y831243D01*
G02X25518Y831244I-2011J1D01*
G01Y834444D01*
G37*
G36*
G01Y821845D02*
G02X29540I2011J0D01*
G01Y818644D01*
G02X25518Y818645I-2011J1D01*
G01Y821845D01*
G37*
G36*
G01Y809247D02*
G02X29540I2011J0D01*
G01Y806046D01*
G02X25518Y806047I-2011J1D01*
G01Y809247D01*
G37*
G36*
G01Y796648D02*
G02X29540I2011J0D01*
G01Y793447D01*
G02X25518Y793448I-2011J1D01*
G01Y796648D01*
G37*
G36*
G01X17988Y790347D02*
G02X22012I2012J0D01*
G01Y787146D01*
G02X17988Y787147I-2012J1D01*
G01Y790347D01*
G37*
G36*
G01Y802946D02*
G02X22012I2012J0D01*
G01Y799745D01*
G02X17988Y799746I-2012J1D01*
G01Y802946D01*
G37*
G36*
G01Y815544D02*
G02X22012I2012J0D01*
G01Y812343D01*
G02X17988Y812344I-2012J1D01*
G01Y815544D01*
G37*
G36*
G01Y828143D02*
G02X22012I2012J0D01*
G01Y824942D01*
G02X17988Y824943I-2012J1D01*
G01Y828143D01*
G37*
G36*
G01Y840741D02*
G02X22012I2012J0D01*
G01Y837540D01*
G02X17988Y837541I-2012J1D01*
G01Y840741D01*
G37*
G36*
G01X25518Y774601D02*
G02X29540I2011J0D01*
G01Y771400D01*
G02X25518Y771401I-2011J1D01*
G01Y774601D01*
G37*
G36*
G01Y762003D02*
G02X29540I2011J0D01*
G01Y758802D01*
G02X25518Y758803I-2011J1D01*
G01Y762003D01*
G37*
G36*
G01Y730507D02*
G02X29540I2011J0D01*
G01Y727306D01*
G02X25518Y727307I-2011J1D01*
G01Y730507D01*
G37*
G36*
G01Y717908D02*
G02X29540I2011J0D01*
G01Y714707D01*
G02X25518Y714708I-2011J1D01*
G01Y717908D01*
G37*
G36*
G01X17988Y768300D02*
G02X22012I2012J0D01*
G01Y765099D01*
G02X17988Y765100I-2012J1D01*
G01Y768300D01*
G37*
G36*
G01Y755702D02*
G02X22012I2012J0D01*
G01Y752501D01*
G02X17988Y752502I-2012J1D01*
G01Y755702D01*
G37*
G36*
G01Y724206D02*
G02X22012I2012J0D01*
G01Y721005D01*
G02X17988Y721006I-2012J1D01*
G01Y724206D01*
G37*
G36*
G01Y711607D02*
G02X22012I2012J0D01*
G01Y708406D01*
G02X17988Y708407I-2012J1D01*
G01Y711607D01*
G37*
G36*
G01Y636017D02*
G02X22012I2012J0D01*
G01Y632816D01*
G02X17988Y632817I-2012J1D01*
G01Y636017D01*
G37*
G36*
G01Y699009D02*
G02X22012I2012J0D01*
G01Y695808D01*
G02X17988Y695809I-2012J1D01*
G01Y699009D01*
G37*
G36*
G01X25518Y642518D02*
G02X29540I2011J0D01*
G01Y639317D01*
G02X25518Y639318I-2011J1D01*
G01Y642518D01*
G37*
G36*
G01Y667715D02*
G02X29540I2011J0D01*
G01Y664514D01*
G02X25518Y664515I-2011J1D01*
G01Y667715D01*
G37*
G36*
G01Y680313D02*
G02X29540I2011J0D01*
G01Y677112D01*
G02X25518Y677113I-2011J1D01*
G01Y680313D01*
G37*
G36*
G01Y692911D02*
G02X29540I2011J0D01*
G01Y689710D01*
G02X25518Y689711I-2011J1D01*
G01Y692911D01*
G37*
G36*
G01Y705510D02*
G02X29540I2011J0D01*
G01Y702309D01*
G02X25518Y702310I-2011J1D01*
G01Y705510D01*
G37*
G36*
G01X17988Y686410D02*
G02X22012I2012J0D01*
G01Y683209D01*
G02X17988Y683210I-2012J1D01*
G01Y686410D01*
G37*
G36*
G01Y673812D02*
G02X22012I2012J0D01*
G01Y670611D01*
G02X17988Y670612I-2012J1D01*
G01Y673812D01*
G37*
G36*
G01Y661213D02*
G02X22012I2012J0D01*
G01Y658012D01*
G02X17988Y658013I-2012J1D01*
G01Y661213D01*
G37*
G36*
G01Y648615D02*
G02X22012I2012J0D01*
G01Y645414D01*
G02X17988Y645415I-2012J1D01*
G01Y648615D01*
G37*
G36*
G01X25518Y617271D02*
G02X29540I2011J0D01*
G01Y614070D01*
G02X25518Y614071I-2011J1D01*
G01Y617271D01*
G37*
G36*
G01Y604722D02*
G02X29540I2011J0D01*
G01Y601521D01*
G02X25518Y601522I-2011J1D01*
G01Y604722D01*
G37*
G36*
G01Y629919D02*
G02X29540I2011J0D01*
G01Y626718D01*
G02X25518Y626719I-2011J1D01*
G01Y629919D01*
G37*
G36*
G01X17988Y623418D02*
G02X22012I2012J0D01*
G01Y620217D01*
G02X17988Y620218I-2012J1D01*
G01Y623418D01*
G37*
G36*
G01Y610820D02*
G02X22012I2012J0D01*
G01Y607619D01*
G02X17988Y607620I-2012J1D01*
G01Y610820D01*
G37*
G36*
G01X41372Y281496D02*
Y278851D01*
G03X42676Y275161I5875J1D01*
G02X24253I-9212J-7446D01*
G03X25556Y278851I-4571J3689D01*
G01Y281496D01*
G02X41372I7908J0D01*
G37*
G54D34*
X82087Y28858D03*
Y178464D03*
Y434370D03*
Y583976D03*
Y839882D03*
Y989488D03*
Y1245394D03*
Y1395000D03*
Y1650906D03*
Y1800512D03*
X162008Y191614D03*
Y341220D03*
Y597126D03*
Y746732D03*
Y1002638D03*
Y1152244D03*
Y1408150D03*
Y1557756D03*
Y1813662D03*
Y1963268D03*
X890354Y191614D03*
Y341220D03*
Y597126D03*
Y746732D03*
Y1002638D03*
Y1152244D03*
Y1408150D03*
Y1557756D03*
Y1813662D03*
Y1963268D03*
G54D33*
X25499Y1950499D03*
X1010999Y43999D03*
X1010499Y1950499D03*
G54D31*
X11811Y571426D03*
Y949378D03*
Y1067489D03*
Y1484811D03*
Y1445441D03*
Y1862763D03*
G54D55*
X1023228Y1416024D03*
Y1694212D03*
G54D46*
X387415Y818188D03*
X352585Y1199532D03*
G54D43*
X373936Y847415D03*
G54D39*
X381813Y382585D03*
X373937Y1184085D03*
G54D45*
X387415Y826062D03*
Y1703936D03*
G54D38*
X373938Y382585D03*
Y417415D03*
X381812D03*
Y812585D03*
G54D32*
X33469Y1029523D03*
X269690Y1490152D03*
G54D47*
X373937Y812585D03*
G54D40*
X356229Y417415D03*
G54D53*
X356238Y1717415D03*
G54D54*
X356232Y1682576D03*
G54D52*
X373938Y1218915D03*
X364092Y1717415D03*
G54D51*
X356291Y1218915D03*
G54D36*
X356230Y382585D03*
G54D48*
X387415Y1213315D03*
Y1711809D03*
G54D42*
X356232Y847415D03*
G54D41*
X364091Y417415D03*
X364089Y847415D03*
X381811Y1218915D03*
G54D44*
X381810Y847415D03*
X364090Y1682585D03*
G54D35*
X352585Y398032D03*
Y828032D03*
Y1698030D03*
G54D50*
X381810Y1184085D03*
X364090Y1218915D03*
G54D49*
X387415Y1205437D03*
G54D37*
X364091Y382585D03*
G54D22*
X72835Y17047D03*
Y190275D03*
Y422559D03*
Y595787D03*
Y828071D03*
Y1001299D03*
Y1233583D03*
Y1406811D03*
Y1639095D03*
Y1812323D03*
X171260Y179803D03*
Y353031D03*
Y585315D03*
Y758543D03*
Y990827D03*
Y1164055D03*
Y1396339D03*
Y1569567D03*
Y1801851D03*
Y1975079D03*
X899606Y179803D03*
Y353031D03*
Y585315D03*
Y758543D03*
Y990827D03*
Y1164055D03*
Y1396339D03*
Y1569567D03*
Y1801851D03*
Y1975079D03*
G54D16*
X20000Y607620D03*
Y610820D03*
Y620218D03*
Y623418D03*
X27529Y601522D03*
Y604722D03*
Y614071D03*
Y617271D03*
Y626719D03*
Y629919D03*
X20000Y658013D03*
Y661213D03*
Y670612D03*
Y673812D03*
Y683210D03*
Y686410D03*
Y632817D03*
Y636017D03*
Y695809D03*
Y699009D03*
Y645415D03*
Y648615D03*
X27529Y664515D03*
Y667715D03*
Y677113D03*
Y680313D03*
Y689711D03*
Y692911D03*
Y702310D03*
Y639318D03*
Y642518D03*
X20000Y708407D03*
Y711607D03*
Y721006D03*
Y724206D03*
Y752502D03*
Y755702D03*
Y765100D03*
Y768300D03*
X27529Y714708D03*
Y717908D03*
Y727307D03*
Y730507D03*
Y758803D03*
Y762003D03*
Y705510D03*
Y771401D03*
Y774601D03*
X27699Y737535D03*
X20000Y837541D03*
Y840741D03*
Y787147D03*
Y790347D03*
Y799746D03*
Y802946D03*
Y812344D03*
Y815544D03*
Y824943D03*
Y828143D03*
X27529Y843642D03*
Y846842D03*
Y793448D03*
Y796648D03*
Y806047D03*
Y809247D03*
Y818645D03*
Y821845D03*
Y831244D03*
Y834444D03*
X20000Y900533D03*
Y903733D03*
Y850139D03*
Y853339D03*
Y913132D03*
Y916332D03*
Y862738D03*
Y865938D03*
Y875336D03*
Y878536D03*
X27529Y894236D03*
Y897436D03*
Y856241D03*
Y859441D03*
Y906834D03*
Y910034D03*
Y868839D03*
Y872039D03*
Y881487D03*
Y884687D03*
X34872Y890906D03*
X30000Y991000D03*
X23291Y1062791D03*
X20000Y1103683D03*
Y1106883D03*
Y1116281D03*
Y1119481D03*
X27529Y1135181D03*
Y1138381D03*
Y1097585D03*
Y1100785D03*
Y1110184D03*
Y1113384D03*
X32335Y1122002D03*
X37396Y1130912D03*
X33971Y1131741D03*
X20000Y1141478D03*
Y1144678D03*
Y1191872D03*
Y1195072D03*
Y1154076D03*
Y1157276D03*
Y1204470D03*
Y1207670D03*
Y1166675D03*
Y1169875D03*
Y1179273D03*
Y1182473D03*
X27529Y1185574D03*
Y1188774D03*
Y1147779D03*
Y1150979D03*
Y1198173D03*
Y1201373D03*
Y1160378D03*
Y1163578D03*
Y1210771D03*
Y1172976D03*
Y1176176D03*
X20000Y1261163D03*
Y1264363D03*
Y1273761D03*
Y1276961D03*
Y1217069D03*
Y1220269D03*
Y1248565D03*
Y1251765D03*
X27529Y1254866D03*
Y1258066D03*
Y1267464D03*
Y1270664D03*
Y1280063D03*
Y1283263D03*
Y1213971D03*
Y1223370D03*
Y1226570D03*
X33201Y1230674D03*
X32959Y1234478D03*
X36000Y1236000D03*
X20000Y1321006D03*
Y1324206D03*
Y1333604D03*
Y1336804D03*
Y1346202D03*
Y1349402D03*
Y1286360D03*
Y1289560D03*
Y1298958D03*
Y1302158D03*
X27529Y1314908D03*
Y1318108D03*
Y1327507D03*
Y1330707D03*
Y1340105D03*
Y1343305D03*
Y1352704D03*
Y1355904D03*
Y1292661D03*
Y1295861D03*
X36170Y1308434D03*
X33699Y1301782D03*
X26500Y1305121D03*
X33938Y1311000D03*
X38500D03*
X30000Y1305000D03*
X30700Y1308600D03*
X20000Y1371399D03*
Y1374599D03*
Y1383998D03*
Y1387198D03*
Y1396596D03*
Y1399796D03*
Y1358801D03*
Y1362001D03*
Y1409195D03*
Y1412395D03*
X27529Y1365102D03*
Y1368302D03*
Y1377700D03*
Y1380900D03*
Y1390299D03*
Y1393499D03*
Y1402897D03*
Y1406097D03*
X27000Y1417500D03*
X32500Y1417600D03*
X28000Y1444000D03*
X20000Y1530454D03*
Y1533654D03*
Y1543052D03*
Y1546252D03*
Y1555650D03*
Y1558850D03*
Y1568249D03*
Y1571449D03*
X27529Y1524156D03*
Y1527356D03*
Y1536755D03*
Y1539955D03*
Y1549353D03*
Y1552553D03*
Y1561952D03*
Y1565152D03*
X33001Y1518123D03*
X36201D03*
X20000Y1640690D03*
Y1643890D03*
Y1593496D03*
Y1590296D03*
Y1606094D03*
Y1602894D03*
Y1618693D03*
Y1615493D03*
Y1631291D03*
Y1628091D03*
X27529Y1634393D03*
Y1637593D03*
Y1587199D03*
Y1583999D03*
Y1599797D03*
Y1596597D03*
Y1612396D03*
Y1609196D03*
Y1624994D03*
Y1621794D03*
X20000Y1716331D03*
Y1713131D03*
Y1665887D03*
Y1669087D03*
Y1678485D03*
Y1681685D03*
Y1691083D03*
Y1694283D03*
X27529Y1719623D03*
Y1672379D03*
Y1675579D03*
Y1684977D03*
Y1688177D03*
Y1697576D03*
Y1700776D03*
X35900Y1706000D03*
X34224Y1709000D03*
X38000Y1715000D03*
X20000Y1728929D03*
Y1725729D03*
Y1741528D03*
Y1738328D03*
Y1754126D03*
Y1750926D03*
X27529Y1722823D03*
Y1735421D03*
Y1732221D03*
Y1748020D03*
Y1744820D03*
Y1760618D03*
Y1757418D03*
X25500Y1769558D03*
X28700D03*
X30200Y1970300D03*
X96000Y119000D03*
X99500Y95940D03*
Y91540D03*
Y77042D03*
Y72642D03*
Y58244D03*
Y53844D03*
X105000Y104788D03*
Y101588D03*
Y85891D03*
Y82691D03*
Y66993D03*
Y63793D03*
X72500Y61161D03*
X71000Y125236D03*
X68000Y128359D03*
Y131559D03*
X99500Y146333D03*
Y141933D03*
X105000Y155182D03*
Y151982D03*
X99300Y201000D03*
X60306Y212338D03*
X80153Y230246D03*
X85427Y239715D03*
X100400Y208300D03*
X70500Y242988D03*
X80300Y234465D03*
X97400Y220200D03*
X66610Y295956D03*
X56024Y292549D03*
X110000Y362500D03*
X106500D03*
X110000Y366000D03*
X106500D03*
X92700Y358400D03*
X52066Y370649D03*
X99500Y482554D03*
Y478154D03*
Y463656D03*
Y459256D03*
X105000Y472505D03*
Y469305D03*
X72500Y466673D03*
X71000Y530748D03*
X96000Y524000D03*
X68000Y533871D03*
Y537071D03*
X99500Y551845D03*
Y547445D03*
Y501452D03*
Y497052D03*
X105000Y557494D03*
Y510300D03*
Y507100D03*
Y491403D03*
Y488203D03*
X71000Y524464D03*
X89400Y603250D03*
X95900Y605500D03*
X62426Y607740D03*
X105000Y560694D03*
X88600Y623300D03*
X80153Y635758D03*
X85223Y645227D03*
X70500Y648500D03*
X48000Y649500D03*
X46500Y653500D03*
X80300Y639977D03*
X50560Y653500D03*
X106500Y771500D03*
X110000D03*
Y768000D03*
X106500D03*
X86900Y774750D03*
X49500Y771000D03*
X80215Y777137D03*
X47500Y901500D03*
X99500Y906964D03*
Y902564D03*
Y888066D03*
Y883666D03*
Y869168D03*
Y864768D03*
X105000Y915812D03*
Y912612D03*
Y896915D03*
Y893715D03*
Y878017D03*
Y874817D03*
X72500Y872185D03*
X96000Y930000D03*
X71000Y936260D03*
X68000Y939383D03*
Y942583D03*
X99500Y957357D03*
Y952957D03*
X105000Y966206D03*
Y963006D03*
X65500Y927500D03*
X71000Y925500D03*
X93000Y1005700D03*
X81689Y1039600D03*
X77750Y1056750D03*
X96500Y1011200D03*
X64037Y1016654D03*
X74000Y1047500D03*
X41000Y1057500D03*
X81689Y1049400D03*
X106100Y1030000D03*
X42286Y1089500D03*
Y1085500D03*
X67090Y1070360D03*
X41608Y1125065D03*
X39959Y1128308D03*
X110000Y1173500D03*
X106500D03*
X110000Y1177000D03*
X106500D03*
X88500Y1177300D03*
X40097Y1142513D03*
X85300Y1182000D03*
X99500Y1274680D03*
Y1270280D03*
X105000Y1283529D03*
Y1280329D03*
X72500Y1277697D03*
X71000Y1341772D03*
X96000Y1335000D03*
X68000Y1344895D03*
Y1348095D03*
X99500Y1312476D03*
Y1308076D03*
Y1293578D03*
Y1289178D03*
X105000Y1321324D03*
Y1318124D03*
Y1302427D03*
Y1299227D03*
X71000Y1335488D03*
X58900Y1317000D03*
X96250Y1414400D03*
X62962Y1422600D03*
X100000Y1423000D03*
X99900Y1419600D03*
X99500Y1362869D03*
Y1358469D03*
X105000Y1371718D03*
Y1368518D03*
X110000Y1470000D03*
X99300Y1431200D03*
X82748Y1455148D03*
X76750Y1462762D03*
X80153Y1446781D03*
X73000Y1455100D03*
X69365Y1474719D03*
X80300Y1451000D03*
X82005Y1540500D03*
X85808D03*
X110500Y1573200D03*
X107000D03*
X103500D03*
X80465Y1570120D03*
X109050Y1540600D03*
X46893Y1519979D03*
X47368Y1527323D03*
X42644Y1521957D03*
X46845Y1514264D03*
X43000Y1526000D03*
X42960Y1517408D03*
X107000Y1576700D03*
X103500D03*
X110500D03*
X42919Y1583175D03*
X64525Y1591016D03*
X99500Y1713588D03*
Y1717988D03*
Y1694690D03*
Y1699090D03*
Y1675792D03*
Y1680192D03*
X105000Y1704739D03*
Y1707939D03*
Y1685841D03*
Y1689041D03*
X72500Y1683209D03*
X51635Y1665355D03*
X66400Y1706900D03*
X71000Y1747284D03*
X104000Y1747800D03*
X68000Y1750407D03*
Y1753607D03*
X99500Y1763981D03*
Y1768381D03*
X105000Y1774030D03*
Y1777230D03*
Y1723636D03*
Y1726836D03*
X67000Y1738000D03*
X71015D03*
X100300Y1820800D03*
X77159Y1818277D03*
X91036Y1835282D03*
X72123Y1841183D03*
X100287Y1825915D03*
X100300Y1830000D03*
X80600Y1848900D03*
X98000Y1848800D03*
X85000Y1817100D03*
X74100Y1796200D03*
X67800Y1855200D03*
X93625Y1802200D03*
X52000Y1877500D03*
X112366Y1883985D03*
X46868Y1887765D03*
X60897Y1885848D03*
X48000Y1877500D03*
X80400Y1957900D03*
X73400D03*
X76900D03*
X87500Y1954300D03*
X80400Y1954400D03*
X83900D03*
X73400D03*
X76900D03*
X57800Y1961800D03*
X177300Y39000D03*
X180800D03*
X184300D03*
X180800Y35500D03*
X177300D03*
X184300D03*
X152400Y41500D03*
X184461Y103368D03*
X125700Y54400D03*
X150557Y142854D03*
X167298Y147703D03*
X159500Y181000D03*
X124000Y128359D03*
Y131559D03*
X167298Y151203D03*
X114579Y137775D03*
X154875Y160500D03*
X173095Y244842D03*
X148000Y241500D03*
X180000Y235394D03*
X176800D03*
X144595Y223745D03*
Y228145D03*
X139095Y214896D03*
Y218096D03*
Y265290D03*
X172900Y249400D03*
X143600Y252100D03*
X129000Y255500D03*
X114295Y338300D03*
X144595Y274138D03*
Y278538D03*
Y293036D03*
Y297436D03*
Y311934D03*
Y316334D03*
X139095Y268490D03*
Y284187D03*
Y287387D03*
Y303085D03*
Y306285D03*
X171595Y308917D03*
X134000Y409500D03*
X137500D03*
X130500D03*
X127000D03*
X117000Y362500D03*
Y366000D03*
X113500Y362500D03*
Y366000D03*
X173800Y379800D03*
X157200Y412000D03*
X158500Y408000D03*
X127000Y413000D03*
X130500D03*
X134000D03*
X137500D03*
X170500Y478500D03*
X125300Y438000D03*
X157750Y541250D03*
X184500Y553500D03*
X124000Y533873D03*
Y537073D03*
X157750Y544750D03*
X159600Y581400D03*
X155500Y574000D03*
X144595Y629257D03*
X139095Y620408D03*
Y623608D03*
X150850Y574350D03*
X148000Y648000D03*
X173095Y650354D03*
X180000Y640906D03*
X176800D03*
X144595Y633657D03*
Y679650D03*
Y684050D03*
Y698548D03*
Y702948D03*
X139095Y670802D03*
Y674002D03*
Y689699D03*
Y692899D03*
X173000Y655200D03*
X117000Y771500D03*
Y768000D03*
X113500Y771500D03*
Y768000D03*
X117945Y743800D03*
X144595Y717446D03*
Y721846D03*
X139095Y708597D03*
Y711797D03*
X171595Y714429D03*
X127000Y818500D03*
X130500D03*
X134000D03*
X137500D03*
X134000Y815000D03*
X137500D03*
X130500D03*
X127000D03*
X156800Y816000D03*
X126800Y842500D03*
X143800Y807400D03*
X178000Y960000D03*
X162200Y988000D03*
X161095Y980622D03*
X167000Y939309D03*
Y942509D03*
X174500Y960000D03*
X157200Y950800D03*
X155900Y954200D03*
X157000Y957500D03*
X161200Y946100D03*
X161700Y950800D03*
X173095Y1055866D03*
X148000Y1053500D03*
X180000Y1046418D03*
X176800D03*
X144595Y1034769D03*
Y1039169D03*
X139095Y1025920D03*
Y1029120D03*
X137500Y1014500D03*
X173000Y1060400D03*
X139300Y1067000D03*
X144595Y1085162D03*
Y1089562D03*
Y1104060D03*
Y1108460D03*
Y1122958D03*
Y1127358D03*
X139095Y1076314D03*
Y1079514D03*
Y1095211D03*
Y1098411D03*
Y1114109D03*
Y1117309D03*
X171595Y1119941D03*
X117000Y1173500D03*
Y1177000D03*
X113500Y1173500D03*
Y1177000D03*
X117900Y1149200D03*
X127000Y1224000D03*
X130500Y1220500D03*
Y1224000D03*
X134000D03*
X137500D03*
X134000Y1220500D03*
X137500D03*
X127000D03*
X158052Y1216052D03*
X129150Y1252050D03*
X147956Y1347802D03*
X129500Y1344821D03*
Y1348021D03*
X154709Y1344513D03*
X140125Y1381300D03*
X167301Y1363238D03*
Y1366838D03*
X158875Y1376100D03*
X118000Y1470000D03*
X148000Y1458000D03*
X126000Y1466000D03*
X173095Y1461378D03*
X180000Y1451930D03*
X176800D03*
X144595Y1440281D03*
Y1444681D03*
Y1490674D03*
Y1495074D03*
X139095Y1431432D03*
Y1434632D03*
Y1481826D03*
Y1485026D03*
Y1500723D03*
X148095Y1468752D03*
X173100Y1466300D03*
X114000Y1573200D03*
X128250Y1506500D03*
X144595Y1509572D03*
Y1513972D03*
Y1528470D03*
Y1532870D03*
X139095Y1503923D03*
Y1519621D03*
Y1522821D03*
X171595Y1525453D03*
X126800Y1630100D03*
X130300D03*
X133800D03*
X126800Y1626600D03*
X130300D03*
X137300Y1630100D03*
Y1626600D03*
X133800D03*
X114000Y1576700D03*
X150200Y1628000D03*
X126900Y1654700D03*
X144400Y1720400D03*
X177717Y1778162D03*
X180075Y1790692D03*
X125000Y1750334D03*
Y1753534D03*
X136500Y1733000D03*
X137000Y1727500D03*
X140825Y1729825D03*
X157898Y1780145D03*
X140300Y1724100D03*
X147200Y1724400D03*
X173095Y1866890D03*
X148000Y1864000D03*
X180000Y1857442D03*
X176800D03*
X144595Y1850193D03*
Y1845793D03*
X139095Y1840144D03*
Y1836944D03*
X151452Y1810000D03*
X144595Y1900586D03*
Y1896186D03*
Y1919484D03*
Y1915084D03*
Y1938382D03*
Y1933982D03*
X139095Y1890538D03*
Y1887338D03*
Y1909435D03*
Y1906235D03*
Y1928333D03*
Y1925133D03*
X171595Y1930965D03*
X113500Y1875970D03*
X173500Y1871700D03*
X137300Y1969900D03*
X136800Y1959900D03*
X150800Y1958900D03*
X150600Y1970300D03*
X187800Y39000D03*
Y35500D03*
X208150Y32250D03*
X220500Y67500D03*
X198800Y158000D03*
Y162500D03*
Y167000D03*
X190500Y238501D03*
Y241701D03*
X188854Y527099D03*
Y530902D03*
X206500Y538750D03*
Y546250D03*
Y531250D03*
X195250Y561300D03*
Y576700D03*
X200250Y572100D03*
X190500Y644013D03*
Y647213D03*
X214700Y784200D03*
X190330Y913530D03*
X198900Y969500D03*
X207350Y968627D03*
X198900Y974000D03*
Y978500D03*
X229500Y946600D03*
X198900Y965477D03*
X208875Y957200D03*
X190500Y1049525D03*
Y1052725D03*
X196000Y1070300D03*
X193400Y1373000D03*
Y1377500D03*
Y1382000D03*
X214500Y1459000D03*
X190500Y1455037D03*
Y1458237D03*
X248500Y1713005D03*
Y1716808D03*
X197900Y1781500D03*
X251900Y1769900D03*
X203299Y1763350D03*
X197900Y1786000D03*
Y1790500D03*
X222500Y1776200D03*
X255495Y1738573D03*
X251692D03*
X203299Y1759750D03*
X224875Y1768100D03*
X190500Y1860549D03*
Y1863749D03*
X292600Y166955D03*
X318656Y391440D03*
X326156D03*
X293000Y385000D03*
X294500Y408000D03*
X315000Y412000D03*
X321400Y404400D03*
X327500Y377000D03*
X321500Y408500D03*
X312500Y393050D03*
X303200Y422600D03*
X313200Y427500D03*
X317000D03*
X321500Y425200D03*
Y417000D03*
Y421000D03*
X296470Y555500D03*
X292667D03*
X297300Y505017D03*
X273500Y597000D03*
Y589000D03*
Y585000D03*
Y577000D03*
X284000Y612000D03*
X273500Y573000D03*
Y565000D03*
X296000Y612000D03*
X292000D03*
X316000D03*
X308000D03*
X304000D03*
X290580Y559000D03*
X298450D03*
X320100Y587200D03*
X317500Y559000D03*
X286130Y615700D03*
X270000Y579030D03*
X310030Y615500D03*
X298030Y621000D03*
X269800Y590930D03*
X270000Y567130D03*
X289933Y615700D03*
X270000Y582833D03*
X313833Y615500D03*
X301833Y621000D03*
X269800Y594733D03*
X270000Y570933D03*
X293500Y738000D03*
X326167Y811099D03*
Y814902D03*
X292000Y837000D03*
X321500Y847000D03*
X315000Y842000D03*
X321500Y838500D03*
X321400Y834400D03*
X327500Y807000D03*
X312000Y824500D03*
X295200Y903000D03*
X305200D03*
Y913000D03*
X295200D03*
X303500Y853100D03*
X321500Y855200D03*
Y851000D03*
X317000Y857900D03*
X313200D03*
X292500Y965500D03*
X294000Y1111500D03*
X321400Y1205900D03*
X321500Y1210000D03*
X327500Y1178500D03*
X312500Y1194000D03*
X295000Y1245000D03*
X294500Y1254000D03*
X302500Y1224000D03*
X321600Y1226600D03*
X313200Y1228800D03*
X317000D03*
X314437Y1213382D03*
X321500Y1222500D03*
Y1218500D03*
X287167Y1380000D03*
X290970D03*
X319500Y1389000D03*
X301400Y1401500D03*
X315500Y1389000D03*
X293100Y1383500D03*
X284900D03*
X273500Y1419500D03*
Y1411500D03*
Y1423500D03*
X326500Y1417500D03*
Y1425700D03*
Y1405400D03*
Y1413500D03*
Y1429700D03*
X328000Y1381500D03*
Y1374000D03*
X327500Y1368500D03*
X273500Y1403500D03*
X307500Y1389000D03*
X330000Y1423470D03*
X270100Y1425697D03*
X330300Y1411100D03*
X270000Y1413530D03*
X330000Y1419667D03*
X270100Y1429500D03*
X330300Y1407297D03*
X270000Y1417333D03*
X273500Y1431500D03*
X287600Y1448000D03*
X279650D03*
X299600D03*
X291600D03*
X326500Y1437700D03*
X311600Y1448000D03*
X303600D03*
X330000Y1435170D03*
X293830Y1451500D03*
X305830Y1451300D03*
X282030Y1451400D03*
X330000Y1431367D03*
X297633Y1451500D03*
X309633Y1451300D03*
X285833Y1451400D03*
X318156Y1692440D03*
X325656D03*
X301800Y1722100D03*
X265500Y1722000D03*
X283500D03*
X285000Y1700600D03*
X295600Y1693400D03*
X285000Y1697400D03*
X292400Y1693400D03*
X315000Y1712000D03*
X321500Y1721000D03*
X327500Y1677000D03*
X321500Y1717000D03*
Y1708500D03*
X321400Y1704400D03*
X313500Y1692500D03*
X276402Y1726146D03*
X272599D03*
X297000Y1777000D03*
Y1752000D03*
X302000D03*
X321500Y1725200D03*
X317000Y1727300D03*
X313200D03*
X363750Y54250D03*
X382200Y81500D03*
X382000Y98000D03*
X358000Y64000D03*
X344500Y71750D03*
X360750Y124000D03*
X369000Y294000D03*
X401500Y410250D03*
X356257Y344176D03*
X391750Y344500D03*
X383750D03*
X348256Y344114D03*
X331500Y389000D03*
X365100Y371200D03*
X397000Y380250D03*
X375200Y371250D03*
X349870Y348870D03*
X331300Y408500D03*
X351729Y455810D03*
X379258Y455892D03*
X387249Y455882D03*
X343729Y455810D03*
X364758Y429249D03*
X375200Y429250D03*
X350137Y451250D03*
X385607Y451232D03*
X339500Y572667D03*
Y576470D03*
X332500Y605000D03*
X336000Y570580D03*
Y578600D03*
X332500Y593000D03*
Y601000D03*
X377250Y774500D03*
X385238Y774122D03*
X331500Y819000D03*
X358800Y803600D03*
X368700Y803750D03*
X388250Y803300D03*
X385196Y779112D03*
X331300Y838500D03*
X402000Y844000D03*
X360100Y808080D03*
X351792Y885835D03*
X379270Y885897D03*
X387292D03*
X343770D03*
X360800Y858500D03*
X375200Y858250D03*
X343894Y880707D03*
X379372Y880728D03*
X391758Y1145676D03*
X383757Y1145655D03*
X331500Y1190500D03*
X364300Y1174900D03*
X374200Y1174750D03*
X391900Y1150250D03*
X331300Y1210000D03*
X398750Y1188250D03*
X359175Y1179640D03*
X351750Y1257380D03*
X379270D03*
X387292Y1257360D03*
X343760Y1257381D03*
X365200Y1229800D03*
X400700Y1237500D03*
X375200Y1229750D03*
X343822Y1252222D03*
X379395Y1252274D03*
X356247Y1644123D03*
X348257Y1644132D03*
X356174Y1649291D03*
X331500Y1691000D03*
X369100Y1673700D03*
X385250Y1673000D03*
X331500Y1708500D03*
X395500Y1690500D03*
X376890Y1678000D03*
X376808Y1755434D03*
X373005D03*
X379000Y1736000D03*
X351750Y1755500D03*
X343750D03*
X383000Y1736300D03*
X365700Y1727700D03*
X383000Y1728700D03*
X375700Y1727750D03*
X343668Y1750741D03*
X379000Y1726000D03*
X405500Y277500D03*
X405000Y289000D03*
X410550Y420500D03*
X425890Y820729D03*
X425891Y812750D03*
X404000Y840500D03*
X420722Y820627D03*
X410550Y850500D03*
X405500Y1192000D03*
X408300Y1237500D03*
X425500Y1215250D03*
Y1223250D03*
X420763Y1223185D03*
X425879Y1721724D03*
X425500Y1713750D03*
X420732Y1721757D03*
X547659Y1560537D03*
X542159D03*
Y1566037D03*
X547659D03*
X663000Y535500D03*
X661500Y650500D03*
X662000Y826600D03*
X665000Y937000D03*
X660000Y1053500D03*
X662000Y1183500D03*
X657000Y1331500D03*
X662000Y1459000D03*
X634200Y1561200D03*
Y1565700D03*
X639700Y1561200D03*
Y1565700D03*
X646200Y1561200D03*
Y1565700D03*
X651700Y1561200D03*
Y1565700D03*
X753500Y1662000D03*
Y1666500D03*
X759000Y1662000D03*
Y1666500D03*
X765500Y1662000D03*
Y1666500D03*
X728700Y1933100D03*
X755995Y1968282D03*
X792343Y193599D03*
X832500Y171000D03*
X824500D03*
X816500D03*
X792343Y197402D03*
X836500Y362500D03*
X833000D03*
X840000Y366000D03*
Y362500D03*
X833000Y366000D03*
X836500D03*
X813350Y369250D03*
X782500Y648000D03*
X840000Y771500D03*
X833000D03*
X836500D03*
X840000Y768000D03*
X836500D03*
X833000D03*
X836500Y1177000D03*
X833000D03*
X840000D03*
Y1582500D03*
X833000D03*
X836500D03*
X840000Y1579000D03*
X836500D03*
X833000D03*
X813000Y1585750D03*
X808500Y1621500D03*
X814000D03*
Y1626000D03*
X808500D03*
X814000Y1630500D03*
X808500D03*
X771000Y1662000D03*
Y1666500D03*
X815000Y1785000D03*
X834750Y1823285D03*
X819000Y1839000D03*
X796339Y1937007D03*
Y1940507D03*
X804239Y1953307D03*
Y1956807D03*
X800739D03*
Y1953307D03*
X797239D03*
Y1956807D03*
X785239Y1960907D03*
X885531Y164804D03*
X896441Y147203D03*
X844000Y190000D03*
X866961Y162539D03*
X896547Y150803D03*
X890469Y164804D03*
X864975Y148875D03*
X876500Y251000D03*
X901441Y244842D03*
X908346Y235394D03*
X905146D03*
X872941Y223745D03*
Y228145D03*
X867441Y214896D03*
Y218096D03*
Y265290D03*
X901600Y249800D03*
X844050Y337300D03*
X872941Y274138D03*
Y278538D03*
Y293036D03*
Y297436D03*
Y311934D03*
Y316334D03*
X867441Y268490D03*
Y284187D03*
Y287387D03*
Y303085D03*
Y306285D03*
X899941Y308917D03*
X843500Y366000D03*
Y362500D03*
X895547Y552715D03*
X857735Y553465D03*
X895547Y556315D03*
X865125Y544000D03*
X883781Y564519D03*
X872941Y629257D03*
X867441Y620408D03*
Y623608D03*
X888719Y564519D03*
X876500Y648000D03*
X901441Y650354D03*
X908346Y640906D03*
X905146D03*
X872941Y633657D03*
Y679650D03*
Y684050D03*
Y698548D03*
Y702948D03*
X867441Y670802D03*
Y674002D03*
Y689699D03*
Y692899D03*
X901200Y655100D03*
X843500Y771500D03*
Y768000D03*
X846200Y743300D03*
X872941Y717446D03*
Y721846D03*
X867441Y708597D03*
Y711797D03*
X899941Y714429D03*
X883781Y970031D03*
X895547Y958227D03*
X857623Y958977D03*
X895547Y961827D03*
X888719Y970031D03*
X865125Y949600D03*
X901441Y1055866D03*
X876500Y1053500D03*
X908346Y1046418D03*
X905146D03*
X872941Y1034769D03*
Y1039169D03*
X867441Y1025920D03*
Y1029120D03*
X901300Y1060700D03*
X872941Y1085162D03*
Y1089562D03*
Y1104060D03*
Y1108460D03*
Y1122958D03*
Y1127358D03*
X867441Y1076314D03*
Y1079514D03*
Y1095211D03*
Y1098411D03*
Y1114109D03*
Y1117309D03*
X899941Y1119941D03*
X843500Y1177000D03*
X844600Y1148700D03*
X865125Y1346488D03*
X883219Y1373504D03*
X895647Y1363738D03*
X857688Y1364488D03*
X895647Y1367338D03*
X887438Y1373374D03*
X901441Y1461378D03*
X876500Y1459000D03*
X908346Y1451930D03*
X905146D03*
X872941Y1440281D03*
Y1444681D03*
Y1490674D03*
Y1495074D03*
X867441Y1431432D03*
Y1434632D03*
Y1481826D03*
Y1485026D03*
Y1500723D03*
X901400Y1466100D03*
X845600Y1554300D03*
X872941Y1509572D03*
Y1513972D03*
Y1528470D03*
Y1532870D03*
X867441Y1503923D03*
Y1519621D03*
Y1522821D03*
X899941Y1525453D03*
X843500Y1582500D03*
Y1579000D03*
X901500Y1681500D03*
X881353Y1650749D03*
X877853D03*
Y1654249D03*
X881353D03*
X896500Y1681000D03*
X859500Y1696000D03*
X898500Y1734000D03*
X910500Y1734600D03*
X895547Y1769250D03*
X883781Y1781054D03*
X895547Y1772850D03*
X888719Y1781054D03*
X865125Y1751800D03*
X902500Y1734000D03*
X910500Y1724700D03*
X876000Y1864000D03*
X901441Y1866890D03*
X908346Y1857442D03*
X905146D03*
X872941Y1845793D03*
Y1850193D03*
X867441Y1836944D03*
Y1840144D03*
X872941Y1896186D03*
Y1900586D03*
Y1915084D03*
Y1919484D03*
Y1933982D03*
Y1938382D03*
X867441Y1887338D03*
Y1890538D03*
Y1906235D03*
Y1909435D03*
Y1925133D03*
Y1928333D03*
X899941Y1930965D03*
X901200Y1871600D03*
X879500Y1970000D03*
X880000Y1955500D03*
X862000Y1969900D03*
Y1960500D03*
X844700Y1945200D03*
X926347Y155500D03*
Y160000D03*
Y164453D03*
X918846Y238501D03*
Y241701D03*
X926365Y561000D03*
Y569965D03*
Y565500D03*
X918846Y644013D03*
Y647213D03*
X926477Y966500D03*
Y971000D03*
Y975477D03*
X918846Y1049525D03*
Y1052725D03*
X926300Y1372000D03*
Y1380988D03*
Y1376500D03*
X918846Y1455037D03*
Y1458237D03*
X959000Y1631000D03*
X943500Y1646989D03*
X973000Y1641500D03*
X931000Y1659000D03*
X959000Y1657000D03*
Y1675000D03*
X926500Y1660000D03*
X941000Y1653000D03*
X934825Y1682285D03*
X947000Y1654500D03*
X915250Y1687500D03*
X919250Y1711500D03*
X926400Y1777500D03*
Y1782000D03*
Y1786500D03*
X921900Y1722400D03*
X918846Y1860549D03*
Y1863749D03*
G54D17*
X25000Y988000D03*
X27825Y995000D03*
X78675Y380704D03*
X47500Y660500D03*
X45000Y1057000D03*
X77607Y1565391D03*
X183344Y808200D03*
X126221Y861250D03*
Y853750D03*
X163170Y1210999D03*
X117387Y1536250D03*
Y1543750D03*
X122844Y1672400D03*
X130344D03*
X213244Y23725D03*
X243156Y382060D03*
X235656D03*
X228156Y438500D03*
X220656D03*
X206700Y575000D03*
X190844Y808200D03*
X242700Y1266656D03*
Y1259156D03*
X232344Y1740000D03*
X239844D03*
X284000Y541344D03*
Y548844D03*
X317156Y1193440D03*
X324656D03*
X276344Y1183060D03*
X268844D03*
X401500Y395500D03*
X393500Y422000D03*
X401500Y830000D03*
X393500Y852000D03*
X402000Y1196500D03*
X396637Y1176000D03*
X358156Y1411000D03*
X350656D03*
X402000Y1695000D03*
X379500Y1673750D03*
X427500Y297156D03*
Y304656D03*
X412500Y1130750D03*
Y1138250D03*
X438656Y1669000D03*
X431156D03*
X458156Y1743000D03*
X450656D03*
X512656Y623500D03*
X520156D03*
X555000Y524344D03*
Y531844D03*
X807756Y377775D03*
X808256Y783275D03*
X807756Y1188775D03*
Y1594275D03*
X979500Y1669750D03*
Y1662250D03*
G54D21*
X7600Y1855000D03*
X17500Y1827500D03*
X22600Y1825200D03*
X17500Y1832500D03*
X22500Y1830000D03*
X17500Y1837500D03*
X22500Y1835000D03*
X17500Y1842500D03*
X22500Y1840000D03*
X17500Y1847500D03*
X22500Y1845000D03*
X17500Y1852500D03*
X22500Y1850000D03*
X17500Y1857500D03*
X22500Y1855000D03*
Y1865000D03*
X17500Y1867500D03*
X22500Y1860000D03*
X12500Y1845000D03*
Y1850000D03*
Y1855000D03*
Y1840000D03*
X17500Y1872500D03*
X22500Y1870000D03*
X12500D03*
X71200Y36900D03*
X136100Y41200D03*
X935000Y1425000D03*
X984900Y1430400D03*
X953800Y1424900D03*
X945000Y1425000D03*
X935000Y1455000D03*
Y1475000D03*
Y1445000D03*
Y1465000D03*
Y1435000D03*
X945000Y1475000D03*
X955000D03*
X965000D03*
X945000Y1465000D03*
X955000D03*
X965000D03*
X945000Y1455000D03*
X955000D03*
X965000D03*
X945000Y1445000D03*
X955000D03*
X965000D03*
X945000Y1435000D03*
X955000D03*
X965000D03*
Y1495000D03*
X955000D03*
X935000Y1485000D03*
Y1495000D03*
X945000D03*
Y1485000D03*
X955000D03*
X965000D03*
X975000Y1495000D03*
Y1485000D03*
Y1475000D03*
Y1465000D03*
Y1455000D03*
Y1445000D03*
Y1435000D03*
X935000Y1505000D03*
X955000D03*
X945000D03*
X965000D03*
X990600Y1427100D03*
X995000Y1425000D03*
X1005000D03*
G54D19*
X36401Y1521623D03*
X32801D03*
X83248Y1059636D03*
X82748Y1465560D03*
X105700Y1548200D03*
X121600Y54700D03*
X148700Y413400D03*
X148600Y818700D03*
X157325Y1223850D03*
X123200Y1947250D03*
X205625Y38750D03*
X288000Y586484D03*
X313000Y559000D03*
X329600Y583200D03*
X332500Y597000D03*
Y589000D03*
X829388Y1695500D03*
X825388D03*
X833388D03*
X837388D03*
X825388Y1739500D03*
X829388D03*
X833388D03*
X837388D03*
X841388Y1695500D03*
X873962Y1672000D03*
Y1676500D03*
Y1681500D03*
Y1685500D03*
X906000Y1713500D03*
X891000Y1720000D03*
X916500Y1729500D03*
G54D11*
X20000Y40000D03*
Y20000D03*
X5500Y40982D03*
Y20982D03*
X10018Y5500D03*
X30018D03*
X20000Y80000D03*
Y100000D03*
Y120000D03*
Y60000D03*
X5500Y120982D03*
Y100982D03*
Y80982D03*
Y60982D03*
X20000Y160000D03*
Y180000D03*
Y140000D03*
X5500Y180982D03*
Y160982D03*
Y140982D03*
X20000Y240000D03*
Y200000D03*
Y220000D03*
X5500Y260982D03*
Y240982D03*
Y220982D03*
Y200982D03*
X23426Y281496D03*
X24764Y286496D03*
X28426Y290197D03*
X38465D03*
X42166Y286496D03*
X5500Y320982D03*
Y300982D03*
Y280982D03*
X20000Y380000D03*
Y400000D03*
X5500Y400982D03*
Y380982D03*
Y360982D03*
Y340982D03*
X20000Y340000D03*
Y460000D03*
Y440000D03*
Y480000D03*
Y420000D03*
X5500Y480982D03*
Y460982D03*
Y440982D03*
Y420982D03*
X20000Y540000D03*
Y500000D03*
Y520000D03*
X5500Y540982D03*
Y520982D03*
Y500982D03*
X24500Y624897D03*
Y612249D03*
Y599700D03*
X16500Y624765D03*
Y618765D03*
Y612166D03*
Y606166D03*
Y598197D03*
X24500Y700488D03*
Y687889D03*
Y675291D03*
Y662693D03*
Y637496D03*
X16500Y700355D03*
Y694355D03*
Y687757D03*
Y681757D03*
Y675158D03*
Y669158D03*
Y662226D03*
Y657000D03*
Y649500D03*
Y644530D03*
Y637363D03*
Y631363D03*
X24500Y769579D03*
Y756981D03*
Y725485D03*
Y712886D03*
X16500Y769646D03*
Y763646D03*
Y757048D03*
Y725552D03*
Y719552D03*
Y712953D03*
Y706953D03*
Y751658D03*
Y732500D03*
X24500Y841820D03*
Y829422D03*
Y816823D03*
Y804225D03*
Y791626D03*
X16500Y848686D03*
Y842087D03*
Y836087D03*
Y829489D03*
Y823489D03*
Y816891D03*
Y810891D03*
Y804292D03*
Y798292D03*
Y791694D03*
Y785694D03*
Y777725D03*
X24500Y905012D03*
Y892414D03*
Y879665D03*
Y867017D03*
Y854419D03*
X16500Y917678D03*
Y911678D03*
Y905079D03*
Y899079D03*
Y879883D03*
Y873883D03*
Y867284D03*
Y861284D03*
Y854686D03*
Y889500D03*
X36000Y960000D03*
X20000Y980000D03*
Y960000D03*
Y940000D03*
X16000Y931000D03*
X34500Y925000D03*
X5500Y980299D03*
X36500Y999500D03*
X5500Y1040299D03*
Y1020299D03*
Y1000299D03*
X24500Y1102601D03*
Y1115200D03*
X16500Y1140024D03*
Y1120828D03*
Y1114828D03*
Y1108229D03*
Y1102229D03*
Y1133500D03*
Y1094260D03*
X31707Y1086000D03*
X24500Y1203189D03*
Y1190590D03*
Y1177992D03*
Y1165394D03*
Y1152795D03*
Y1140197D03*
X16500Y1209016D03*
Y1203016D03*
Y1196418D03*
Y1190418D03*
Y1183820D03*
Y1177820D03*
Y1171221D03*
Y1165221D03*
Y1158623D03*
Y1152623D03*
Y1146024D03*
X24500Y1285079D03*
Y1272480D03*
Y1259882D03*
Y1228386D03*
Y1215787D03*
X16500Y1284906D03*
Y1278308D03*
Y1272308D03*
Y1265709D03*
Y1259709D03*
Y1253111D03*
Y1247721D03*
Y1221615D03*
Y1215615D03*
Y1228500D03*
X24500Y1357720D03*
Y1345121D03*
Y1332523D03*
Y1319924D03*
Y1297677D03*
X16500Y1357347D03*
Y1350749D03*
Y1344749D03*
Y1338150D03*
Y1332150D03*
Y1325552D03*
Y1319552D03*
Y1303505D03*
Y1297505D03*
Y1290906D03*
X16417Y1311583D03*
X24500Y1407913D03*
Y1395315D03*
Y1382716D03*
Y1370118D03*
X16500Y1413741D03*
Y1407741D03*
Y1401142D03*
Y1395142D03*
Y1388544D03*
Y1382544D03*
Y1375946D03*
Y1369946D03*
Y1363347D03*
X24500Y1560197D03*
Y1547598D03*
Y1522401D03*
Y1535000D03*
X16500Y1573000D03*
Y1566500D03*
Y1560500D03*
Y1554000D03*
Y1548000D03*
Y1541500D03*
Y1535000D03*
Y1529000D03*
Y1521031D03*
Y1512500D03*
X24500Y1632638D03*
Y1620039D03*
Y1607441D03*
Y1594842D03*
Y1582244D03*
X16500Y1644735D03*
Y1639845D03*
Y1633000D03*
Y1626500D03*
Y1620000D03*
Y1614000D03*
Y1607500D03*
Y1601500D03*
Y1595000D03*
Y1588500D03*
Y1582500D03*
X24500Y1717868D03*
Y1695821D03*
Y1683222D03*
Y1670624D03*
X16500Y1669933D03*
Y1677000D03*
Y1683170D03*
Y1689500D03*
Y1696000D03*
Y1702500D03*
Y1712000D03*
Y1717462D03*
Y1665044D03*
X24500Y1755663D03*
Y1743065D03*
Y1730466D03*
X22219Y1768323D03*
X16500Y1749000D03*
Y1756052D03*
Y1765000D03*
Y1774500D03*
Y1784000D03*
Y1790500D03*
Y1724000D03*
Y1730658D03*
Y1736500D03*
Y1743356D03*
X39500Y1823300D03*
X39400Y1819900D03*
X38400Y1846750D03*
X38300Y1859050D03*
X38800Y1810100D03*
X22100Y1802800D03*
X38317Y1804491D03*
X34900Y1807200D03*
X35100Y1813000D03*
X26500Y1805200D03*
X26600Y1810600D03*
X26300Y1815000D03*
X30800Y1805300D03*
Y1810500D03*
X17500Y1801900D03*
X22000Y1814100D03*
Y1809100D03*
X17500Y1806900D03*
Y1811900D03*
Y1816500D03*
X11615Y1922835D03*
X12953Y1927835D03*
X16615Y1931536D03*
X26654D03*
X30355Y1927835D03*
X31693Y1922835D03*
X5500Y1880685D03*
Y1888685D03*
X38500Y1871350D03*
X38200Y1883800D03*
X19974Y1943969D03*
X33700Y1960300D03*
X20000Y1960000D03*
Y1980000D03*
X32559Y1986626D03*
X12559D03*
X5500Y1973685D03*
Y1953685D03*
X40000Y40000D03*
Y20000D03*
X90018Y5500D03*
X110018D03*
X50018D03*
X70018D03*
X60000Y80000D03*
X40000D03*
Y100000D03*
Y120000D03*
Y60000D03*
X109038Y68476D03*
X109000Y87476D03*
X109160Y100476D03*
X96000Y114212D03*
Y107913D03*
Y98464D03*
Y89015D03*
Y79567D03*
Y70118D03*
Y60868D03*
X96100Y52300D03*
X72500Y91161D03*
Y86161D03*
X100000Y180000D03*
X99800Y194200D03*
X40000Y160000D03*
Y180000D03*
Y140000D03*
X67500Y135830D03*
X108917Y156976D03*
X72500Y166161D03*
X96000Y158307D03*
X72500Y151161D03*
X96000Y148858D03*
X72500Y136161D03*
X96000Y139409D03*
Y134000D03*
Y123661D03*
X104000Y125000D03*
X85250Y247238D03*
X80000Y200000D03*
X77306Y259381D03*
X40000Y240000D03*
Y200000D03*
Y220000D03*
X43504Y281496D03*
X109044Y473988D03*
X96000Y485079D03*
Y475630D03*
Y466181D03*
Y456732D03*
X67500Y541342D03*
X109000Y492988D03*
X109138Y511488D03*
X72500Y556673D03*
X96000Y554369D03*
X72500Y541673D03*
X96000Y544921D03*
Y539500D03*
Y529173D03*
Y519724D03*
Y513425D03*
Y503976D03*
Y494527D03*
X72500Y496673D03*
Y491673D03*
X104000Y531000D03*
X61100Y600100D03*
X80000Y600000D03*
X108917Y562488D03*
X72500Y571673D03*
X96000Y563819D03*
X85250Y652750D03*
X61500Y682500D03*
X102500Y737500D03*
X83200Y768300D03*
X76000Y706500D03*
X67500Y822500D03*
X51000Y913500D03*
X63500Y899000D03*
X65500Y867500D03*
X109040Y879500D03*
X109000Y898500D03*
X109187Y917000D03*
X96000Y918937D03*
Y909488D03*
Y900039D03*
Y890591D03*
Y881142D03*
Y871692D03*
Y862244D03*
X72500Y902185D03*
Y897185D03*
X67000Y953500D03*
X96532Y977682D03*
X107400Y994000D03*
X67500Y946855D03*
X109000Y968000D03*
X72500Y977185D03*
X96000Y969331D03*
X72500Y962185D03*
X96000Y959882D03*
X72500Y947185D03*
X96000Y950433D03*
Y945000D03*
Y934685D03*
Y925236D03*
X104000Y936000D03*
X99600Y1001400D03*
X102403Y1058209D03*
X103200Y1042500D03*
X71000Y1109000D03*
X111500Y1145000D03*
X109040Y1285012D03*
X96000Y1277205D03*
Y1267756D03*
X67500Y1352366D03*
X109000Y1304012D03*
X109133Y1322512D03*
X72500Y1352697D03*
X96000Y1355945D03*
Y1350500D03*
Y1340197D03*
Y1330748D03*
Y1324449D03*
Y1315000D03*
Y1305551D03*
Y1296103D03*
Y1286654D03*
X72500Y1307697D03*
Y1302697D03*
X104000Y1341000D03*
X109000Y1373512D03*
X70838Y1384165D03*
X96000Y1374843D03*
X72285Y1365633D03*
X96000Y1365393D03*
X80000Y1480000D03*
X109500Y1486000D03*
X90500Y1521500D03*
X96000Y1541100D03*
X72000Y1551500D03*
X72100Y1536400D03*
Y1509900D03*
X64500Y1581500D03*
X40500Y1608500D03*
X66500Y1694000D03*
X68000Y1651500D03*
X109040Y1690524D03*
X109000Y1709524D03*
X96000Y1701615D03*
Y1711063D03*
Y1673268D03*
X72500Y1708209D03*
X96000Y1682716D03*
Y1692166D03*
X72500Y1713209D03*
X96000Y1720512D03*
X100000Y1780000D03*
X67500Y1746128D03*
X109137Y1728024D03*
X109030Y1772524D03*
X96000Y1729961D03*
Y1736260D03*
Y1745109D03*
Y1755158D03*
Y1761457D03*
Y1770906D03*
X72500Y1758209D03*
Y1773209D03*
Y1788209D03*
X96000Y1780355D03*
X100000Y1759000D03*
X93600Y1848200D03*
X45100Y1850800D03*
X42300Y1846750D03*
X42200Y1859050D03*
X45200Y1839300D03*
Y1843300D03*
Y1854700D03*
X40800Y1832300D03*
Y1827300D03*
X76975Y1864000D03*
X100000Y1928000D03*
X80000D03*
X60000D03*
X74300Y1900000D03*
X107543Y1898024D03*
X111000Y1879570D03*
X100100Y1896300D03*
X80000Y1920000D03*
X60000D03*
Y1900000D03*
X44000D03*
X40556Y1917072D03*
X40000Y1940000D03*
X52000Y1887500D03*
X41700Y1883700D03*
X42100Y1871350D03*
X110700Y1974100D03*
X80000Y1980000D03*
X100300Y1980900D03*
X71666Y1961325D03*
X40000Y1980000D03*
X112559Y1986626D03*
X92559D03*
X72559D03*
X52559D03*
X94700Y1974100D03*
X98800D03*
X103300D03*
X107000D03*
X123819Y17717D03*
X125157Y22717D03*
X128819Y26418D03*
X138858D03*
X142559Y22717D03*
X143897Y17717D03*
X155018Y5500D03*
X170018D03*
X116600Y46800D03*
X180000Y80000D03*
X160000D03*
X140000D03*
X154700Y65000D03*
X150200D03*
X141700Y64900D03*
X138200D03*
X131700Y61300D03*
X128200D03*
X179147Y137913D03*
X180000Y180000D03*
X124000Y135859D03*
Y124059D03*
X147125Y160500D03*
X158300Y135200D03*
X176492Y231103D03*
X180100Y231095D03*
X140000Y247500D03*
X145800Y332400D03*
X131300D03*
X173000Y312500D03*
X131300Y335900D03*
X126445Y338300D03*
X124466Y370025D03*
X143500Y370000D03*
X147000D03*
X139500D03*
X136000D03*
X180000Y480000D03*
Y460000D03*
X120000D03*
X140000Y480000D03*
Y460000D03*
X160000Y440000D03*
X140000D03*
X120800Y438000D03*
X157500Y551200D03*
X160000Y520000D03*
X180000D03*
X124000Y541373D03*
Y529573D03*
X165138Y536500D03*
X174000Y553500D03*
X131500Y610500D03*
X180000Y620000D03*
Y580000D03*
X139500Y600400D03*
X180000Y600000D03*
X132350Y563750D03*
X176492Y636617D03*
X180308D03*
X140000Y654000D03*
X124966Y775525D03*
X125500Y719000D03*
X180000Y720000D03*
X136100Y775600D03*
X139600D03*
X147100D03*
X143600D03*
X145800Y737100D03*
X131400Y738200D03*
X173000Y718000D03*
X131400Y741700D03*
X122445Y743800D03*
X116000Y814500D03*
X122251Y842400D03*
X160000Y880000D03*
X140000Y900000D03*
X180000Y980000D03*
X167000Y945909D03*
Y935909D03*
X180000Y1000000D03*
X176492Y1042129D03*
X180308D03*
X140000Y1059500D03*
X129000Y1051500D03*
X180000Y1140000D03*
X129500Y1084500D03*
X122500Y1107000D03*
X123500Y1123500D03*
X180000Y1120000D03*
Y1100000D03*
Y1080000D03*
X147800Y1140000D03*
X173000Y1123500D03*
X124100Y1181025D03*
X143500Y1180400D03*
X147000D03*
X139500D03*
X136000D03*
X131500Y1143200D03*
Y1146700D03*
X122400Y1149200D03*
X120000Y1280000D03*
X140000D03*
X160000D03*
X180000D03*
X120000Y1220000D03*
X180000D03*
X118250Y1252050D03*
X179147Y1353048D03*
X160000Y1340000D03*
X180000D03*
X140000D03*
Y1300000D03*
X160000D03*
X180000D03*
X129500Y1352321D03*
Y1340521D03*
X121320Y1425396D03*
X117690Y1397168D03*
X143087Y1403623D03*
X180000Y1400000D03*
Y1420000D03*
X160000Y1360000D03*
X151125Y1376608D03*
X126916Y1447364D03*
X180000Y1440000D03*
Y1500000D03*
X176492Y1447634D03*
X180308D03*
X130000Y1470000D03*
X122000D03*
X114000D03*
X140000Y1464000D03*
X147700Y1545500D03*
X123400Y1522600D03*
X116500Y1505500D03*
X180000Y1520000D03*
X130600Y1549100D03*
X173000Y1529000D03*
X123500Y1505200D03*
X144200Y1545500D03*
X113841Y1580900D03*
X181500Y1641500D03*
X182500Y1622500D03*
X172000Y1595000D03*
X171500Y1613500D03*
X143300Y1586900D03*
X146800D03*
X138800Y1585100D03*
X135300D03*
X160200Y1710300D03*
X117300Y1696500D03*
X136600Y1681900D03*
X121700Y1654800D03*
X143000Y1656000D03*
X137000Y1666500D03*
X120000Y1678000D03*
X123000Y1702000D03*
X136700Y1720100D03*
X160000Y1720000D03*
Y1700000D03*
X180000D03*
Y1680000D03*
X117000Y1654600D03*
X159800Y1730000D03*
X148000Y1787000D03*
X125000Y1757834D03*
Y1746034D03*
X128800Y1854000D03*
X145500Y1807500D03*
X136500Y1811500D03*
X140000Y1820000D03*
X160000Y1800000D03*
X180000D03*
Y1840000D03*
X180308Y1853146D03*
X176492D03*
X128800Y1921300D03*
X129500Y1883500D03*
X115228Y1879770D03*
X128200Y1900300D03*
X180000Y1880000D03*
Y1900000D03*
Y1940000D03*
X173000Y1934500D03*
X140000Y1870000D03*
X133000Y1977100D03*
X114200Y1974100D03*
X118500Y1971400D03*
X139100Y1977100D03*
X172559Y1986626D03*
X152559D03*
X132559D03*
X130500Y1946200D03*
X240000Y20000D03*
Y40000D03*
X230018Y5500D03*
X250018D03*
X190018D03*
X210018D03*
X220000Y80000D03*
X240000D03*
X200000D03*
X240000Y140000D03*
X220000D03*
Y160000D03*
X240000D03*
X200000Y180000D03*
X220000D03*
X240000D03*
X200000Y200000D03*
X240000Y220000D03*
X220000D03*
Y200000D03*
X240000D03*
X200000Y260000D03*
X240000D03*
X220000D03*
X194500Y243300D03*
X200000Y280000D03*
X220000D03*
X240000D03*
Y320000D03*
Y300000D03*
X220000D03*
X200000D03*
Y320000D03*
X220000D03*
X240000Y340000D03*
X220000Y360000D03*
X240000D03*
X220000Y340000D03*
X200000D03*
Y360000D03*
X220000Y480000D03*
X200000D03*
X220000Y460000D03*
X200000D03*
X220000Y420000D03*
X200000Y440000D03*
Y420000D03*
Y520000D03*
X220000D03*
X195500Y531250D03*
Y546250D03*
Y538750D03*
X220000Y620000D03*
X240000Y600000D03*
Y580000D03*
X200000D03*
Y700000D03*
X220000D03*
Y680000D03*
X200000D03*
Y660000D03*
X220000D03*
Y640000D03*
X190500Y651513D03*
X240000Y760000D03*
X220000Y720000D03*
Y740000D03*
X200000Y760000D03*
Y740000D03*
Y720000D03*
Y900000D03*
X240000Y860000D03*
X220000D03*
Y880000D03*
X240000D03*
X194200Y985900D03*
X220000Y940000D03*
X240000D03*
X201125Y957200D03*
X195500Y949750D03*
X220000Y1040000D03*
Y1020000D03*
X240000D03*
Y1000000D03*
Y1060000D03*
X220000D03*
X240000Y1040000D03*
X190600Y1057024D03*
X200000Y1080000D03*
Y1100000D03*
Y1140000D03*
Y1120000D03*
X220000Y1140000D03*
Y1120000D03*
X240000D03*
Y1100000D03*
X220000D03*
Y1080000D03*
X240000D03*
X255674Y1099470D03*
X208500Y1190000D03*
X200000Y1200000D03*
X240000D03*
Y1180000D03*
X200000Y1160000D03*
Y1280000D03*
X220000D03*
X240000D03*
Y1220000D03*
X220000D03*
X200000Y1340000D03*
X220000D03*
X240000D03*
X200000Y1300000D03*
X220000D03*
X240000D03*
X227000Y1359500D03*
X215000Y1368000D03*
X240000Y1367500D03*
Y1420000D03*
Y1400000D03*
Y1460000D03*
Y1440000D03*
X200000D03*
Y1460000D03*
Y1480000D03*
X240000D03*
Y1500000D03*
X200000D03*
X190400Y1450738D03*
X202000Y1534000D03*
X200000Y1520000D03*
X220000D03*
X240000D03*
X200000Y1560000D03*
X220000D03*
X240000D03*
X203500Y1618500D03*
X229500Y1614500D03*
X189300Y1577200D03*
X220000Y1580000D03*
X242500Y1702500D03*
X251800Y1718400D03*
X220000Y1720000D03*
X200000Y1660000D03*
Y1680000D03*
X220000D03*
Y1660000D03*
X240000Y1680000D03*
Y1660000D03*
X220200Y1740900D03*
X206000Y1735000D03*
X256000Y1745500D03*
X220000Y1734500D03*
X207600Y1777500D03*
X220800Y1763750D03*
X191353Y1772940D03*
X200000Y1800000D03*
X220000D03*
X240000D03*
X220000Y1840000D03*
X240000D03*
X194620Y1865000D03*
X200000Y1880000D03*
Y1900000D03*
X220000D03*
X240000Y1920000D03*
X220000D03*
X200000D03*
Y1940000D03*
X220000D03*
X240000D03*
X256549Y1898366D03*
X240000Y1880000D03*
X256500D03*
X200000Y1980000D03*
Y1960000D03*
X220000Y1980000D03*
Y1960000D03*
X240000Y1980000D03*
Y1960000D03*
X252559Y1986626D03*
X232559D03*
X212559D03*
X192559D03*
X300000Y40000D03*
Y20000D03*
X320000D03*
Y40000D03*
X260000D03*
Y20000D03*
X280000D03*
Y40000D03*
X310018Y5500D03*
X330018D03*
X270018D03*
X290018D03*
X320000Y80000D03*
X300000Y60000D03*
X320000D03*
Y120000D03*
X300000D03*
X280000D03*
X260000Y100000D03*
X280000D03*
X300000D03*
X320000D03*
X300000Y80000D03*
X280000D03*
X260000D03*
Y160000D03*
X320000D03*
X300000Y140000D03*
X320000D03*
X260000Y180000D03*
X280000D03*
Y220000D03*
X260000D03*
Y200000D03*
X280000D03*
X300000D03*
Y220000D03*
X320000D03*
Y240000D03*
X265552Y279528D03*
X266890Y284528D03*
X270552Y288229D03*
X280591D03*
X284292Y284528D03*
X285630Y279528D03*
X320000Y320000D03*
X300000D03*
X280000D03*
X260000D03*
X320000Y280000D03*
X300000D03*
X260000Y300000D03*
X280000Y360000D03*
X260000D03*
Y340000D03*
X280000D03*
X300000D03*
X320000D03*
X304553Y374081D03*
X313500Y386000D03*
X309000Y365000D03*
X313500Y362000D03*
X320000Y359500D03*
X327500Y373000D03*
X305100Y407700D03*
X304400Y416200D03*
X280000Y460000D03*
Y480000D03*
X300000D03*
Y460000D03*
X320000D03*
X300000Y440000D03*
X280000D03*
Y420000D03*
X260000D03*
Y440000D03*
Y480000D03*
Y460000D03*
X321500Y413000D03*
X260000Y520000D03*
X320000Y540000D03*
X260000Y560000D03*
Y600000D03*
X280000Y620000D03*
X260000D03*
X302500Y583000D03*
X297500D03*
Y588000D03*
X302500D03*
X300000Y585500D03*
X265552Y685030D03*
X266890Y690030D03*
X270552Y693731D03*
X280591D03*
X284292Y690030D03*
X285630Y685030D03*
X298500Y660200D03*
Y680200D03*
X320000Y700000D03*
X260000D03*
X320000Y640000D03*
X300000D03*
X280000D03*
X260000D03*
X298200Y720000D03*
X260000D03*
X320000D03*
X304400Y846700D03*
X321500Y807000D03*
X297840Y804552D03*
X280000Y820000D03*
X325053Y782652D03*
X309000Y795000D03*
X321500Y843000D03*
X323000Y819500D03*
X313500Y792000D03*
X320000Y789500D03*
X327500Y803000D03*
X304500Y836700D03*
X301300Y822550D03*
X260000Y860000D03*
Y880000D03*
X300000D03*
X280000D03*
Y860000D03*
X260000Y940000D03*
X280000D03*
X300000D03*
X260000Y980000D03*
X280000D03*
X300000D03*
X320000Y1060000D03*
X300000D03*
X260000D03*
Y1040000D03*
X280000D03*
X300000D03*
X320000D03*
Y1020000D03*
X280000D03*
X300000D03*
X260000D03*
X280000Y1000000D03*
X300000D03*
X320000D03*
X265552Y1088573D03*
X266890Y1093573D03*
X270552Y1097274D03*
X280591D03*
X284292Y1093573D03*
X285630Y1088573D03*
X320000Y1140000D03*
X260000Y1120000D03*
X280000D03*
X300000D03*
X320000Y1100000D03*
X300000D03*
Y1080000D03*
X320000D03*
X260000Y1200000D03*
X280000D03*
Y1180000D03*
X260000Y1160000D03*
X296011Y1185470D03*
X309000Y1166500D03*
X295400Y1172655D03*
X313500Y1187500D03*
X320000Y1161000D03*
X327500Y1174500D03*
X305200Y1208300D03*
X304500Y1217500D03*
X320000Y1280000D03*
X300000Y1240000D03*
X320000Y1260000D03*
X300000Y1280000D03*
Y1260000D03*
X280000Y1280000D03*
X260000D03*
Y1260000D03*
X280000D03*
Y1220000D03*
X260000D03*
X321500Y1214500D03*
X280000Y1340000D03*
X260000D03*
X300000Y1300000D03*
X280000D03*
X260000D03*
X311500Y1389000D03*
X280000Y1380000D03*
X260000Y1400000D03*
Y1420000D03*
X300000Y1421500D03*
X302500Y1424000D03*
X297500D03*
Y1419000D03*
X302500D03*
X303500Y1389000D03*
X297600Y1392000D03*
X273500Y1407500D03*
X260000Y1440000D03*
X300984Y1433500D03*
X260000Y1520000D03*
X280000D03*
X300000D03*
X320000Y1540000D03*
Y1560000D03*
X300000D03*
X280000D03*
X260000D03*
X258585Y1508386D03*
X260000Y1620000D03*
Y1600000D03*
X300000Y1620000D03*
X280000Y1600000D03*
Y1620000D03*
X300000Y1600000D03*
X320000D03*
X289300Y1696200D03*
Y1701800D03*
X306200Y1689400D03*
X259000Y1702500D03*
X260000Y1680000D03*
Y1660000D03*
X321500Y1713000D03*
X327500Y1673000D03*
X305300Y1715700D03*
X306200Y1709600D03*
X320000Y1760000D03*
Y1780000D03*
X260000Y1740000D03*
X288000Y1742500D03*
X293000D03*
X284000Y1731250D03*
X268800Y1774600D03*
X260000Y1800000D03*
Y1840000D03*
X280000D03*
X320000Y1860000D03*
X300000D03*
Y1840000D03*
X320000Y1820000D03*
Y1840000D03*
X271500Y1795000D03*
X279500D03*
X287500D03*
X300000Y1800000D03*
X265552Y1903534D03*
X266890Y1908534D03*
X270552Y1912235D03*
X280591D03*
X284292Y1908534D03*
X285630Y1903534D03*
X320000Y1940000D03*
X300000D03*
X280000D03*
X260000D03*
X280071Y1924667D03*
X300000Y1900000D03*
Y1920000D03*
X320000D03*
Y1900000D03*
X300000Y1880000D03*
X320000D03*
X260000Y1980000D03*
Y1960000D03*
X280000Y1980000D03*
Y1960000D03*
X300000Y1980000D03*
Y1960000D03*
X320000Y1980000D03*
Y1960000D03*
X312559Y1986626D03*
X292559D03*
X272559D03*
X380000Y20000D03*
Y40000D03*
X400000D03*
Y20000D03*
X340000Y40000D03*
Y20000D03*
X360000Y40000D03*
Y20000D03*
X390018Y5500D03*
X350018D03*
X370018D03*
X400000Y100000D03*
Y80000D03*
X377500Y98000D03*
X400000Y60000D03*
X340000Y80000D03*
Y100000D03*
Y60000D03*
X400000Y120000D03*
X340000D03*
X373500Y98000D03*
X363750Y65250D03*
X352500Y68500D03*
X358500Y93500D03*
X363750Y73300D03*
X340000Y180000D03*
X360000D03*
X380000D03*
X400000D03*
Y140000D03*
Y160000D03*
X380000Y140000D03*
Y160000D03*
X360000Y140000D03*
Y160000D03*
X340000D03*
Y140000D03*
X357250Y124000D03*
X400000Y220000D03*
Y200000D03*
X380000D03*
X340000Y240000D03*
Y260000D03*
X360000D03*
Y280000D03*
X370000Y411000D03*
Y405500D03*
X375500D03*
X381000D03*
X375500Y411000D03*
X381000D03*
X359000D03*
X364500D03*
Y405500D03*
X359000D03*
X370000Y400000D03*
X381000D03*
X375500D03*
X370000Y389000D03*
Y394500D03*
X375500D03*
Y389000D03*
X381000D03*
Y394500D03*
X364500Y400000D03*
X365000Y394500D03*
Y389000D03*
X359000D03*
Y394500D03*
Y400000D03*
X337500Y406250D03*
X331500Y393000D03*
X401500Y401500D03*
X397000Y383750D03*
X400000Y440000D03*
Y460000D03*
Y480000D03*
X339500Y416750D03*
X370397Y439122D03*
X368500Y436000D03*
X372000D03*
X397000Y414750D03*
X379250Y451000D03*
X385896Y444265D03*
X343750Y451000D03*
X350241Y444377D03*
X400000Y540000D03*
X340000D03*
X380000Y500000D03*
Y540000D03*
X400000Y520000D03*
Y560000D03*
X360000Y580000D03*
X340000Y560000D03*
Y600000D03*
Y620000D03*
X380000D03*
X400000D03*
X380000Y560000D03*
Y660000D03*
X400000Y640000D03*
Y680000D03*
Y700000D03*
X340000Y660000D03*
Y680000D03*
Y700000D03*
X360000D03*
Y680000D03*
Y660000D03*
Y640000D03*
X380000D03*
X400000Y740000D03*
Y720000D03*
X340000Y740000D03*
Y720000D03*
X360000D03*
X400000Y780000D03*
X340000D03*
X370000Y841000D03*
Y835500D03*
X375500D03*
X381000D03*
X375500Y841000D03*
X381000D03*
X359000D03*
X364500D03*
Y835500D03*
X359000D03*
X370000Y830000D03*
X381000D03*
X375500D03*
X370000Y819000D03*
Y824500D03*
X375500D03*
Y819000D03*
X381000D03*
Y824500D03*
X364500Y830000D03*
X365000Y824500D03*
Y819000D03*
X359000D03*
Y824500D03*
Y830000D03*
X397000Y844750D03*
X339500Y846750D03*
X337500Y836250D03*
X331500Y823000D03*
X401500Y836000D03*
X395000Y806500D03*
X371059Y903347D03*
X355622Y919857D03*
X380000Y920000D03*
X400000D03*
Y900000D03*
X368500Y865000D03*
X372000D03*
X379228Y874277D03*
X387250Y881000D03*
X351740Y880717D03*
X343749Y874298D03*
X335823Y940330D03*
X340000Y980000D03*
X360000D03*
X380000D03*
X400000D03*
Y960000D03*
X380000D03*
X340000D03*
X360000D03*
Y940000D03*
X380000D03*
X400000D03*
Y1060000D03*
X380000D03*
X400000Y1040000D03*
X380000D03*
X360000Y1060000D03*
X340000D03*
X360000Y1040000D03*
X340000D03*
Y1000000D03*
Y1020000D03*
X360000Y1000000D03*
Y1020000D03*
X380000Y1000000D03*
Y1020000D03*
X400000Y1000000D03*
Y1020000D03*
X360000Y1140000D03*
X340000D03*
X380000Y1100000D03*
X400000Y1080000D03*
X380000D03*
X360000Y1100000D03*
X340000D03*
X360000Y1080000D03*
X340000D03*
Y1160000D03*
X354228Y1164233D03*
X370000Y1212500D03*
Y1207000D03*
X375500D03*
X381000D03*
X375500Y1212500D03*
X381000D03*
X359000D03*
X364500D03*
Y1207000D03*
X359000D03*
X370000Y1201500D03*
X381000D03*
X375500D03*
X370000Y1190500D03*
Y1196000D03*
X375500D03*
Y1190500D03*
X381000D03*
Y1196000D03*
X364500Y1201500D03*
X365000Y1196000D03*
Y1190500D03*
X359000D03*
Y1196000D03*
Y1201500D03*
X337500Y1207750D03*
X331500Y1194500D03*
X402000Y1202500D03*
X396750Y1181250D03*
X400000Y1280000D03*
Y1260000D03*
X339500Y1218250D03*
X370200Y1239700D03*
X368500Y1236500D03*
X372000D03*
X343749Y1245719D03*
X351771Y1252213D03*
X379249Y1245782D03*
X387208Y1252212D03*
X391500Y1218500D03*
X400000Y1340000D03*
X380000D03*
Y1320000D03*
X400000D03*
X380000Y1300000D03*
X400000D03*
X360000Y1340000D03*
Y1320000D03*
X340000Y1340000D03*
X380000Y1420000D03*
Y1400000D03*
X400000Y1420000D03*
Y1400000D03*
Y1380000D03*
Y1360000D03*
X380000D03*
Y1380000D03*
X360000D03*
Y1360000D03*
X340000D03*
Y1380000D03*
X380000Y1500000D03*
X360000D03*
X340000Y1480000D03*
Y1460000D03*
X400000D03*
X380000Y1440000D03*
X400000D03*
X360000Y1560000D03*
X400000Y1540000D03*
X380000D03*
X360000D03*
Y1520000D03*
X380000D03*
X400000D03*
Y1580000D03*
X380000D03*
X334500Y1650000D03*
Y1665000D03*
X380000Y1660000D03*
X400000D03*
X359000Y1705500D03*
Y1700000D03*
Y1694500D03*
Y1689000D03*
X365000D03*
Y1694500D03*
X364500Y1700000D03*
Y1705500D03*
Y1711000D03*
X359000D03*
X381000D03*
X375500D03*
X381000Y1705500D03*
X375500D03*
X381000Y1694500D03*
Y1689000D03*
X375500D03*
Y1694500D03*
X370000D03*
Y1689000D03*
Y1705500D03*
Y1711000D03*
X381000Y1700000D03*
X375500D03*
X370000D03*
X402000Y1701000D03*
X339500Y1716750D03*
X337500Y1706250D03*
X331500Y1695000D03*
X388750Y1673000D03*
X368500Y1768000D03*
X400000Y1760000D03*
X365400Y1734400D03*
X369000Y1734500D03*
X372500D03*
X393000Y1723500D03*
X351750Y1751000D03*
X343709Y1744187D03*
X400000Y1860000D03*
X380000D03*
X360000D03*
X340000D03*
Y1800000D03*
Y1840000D03*
X360000D03*
X380000D03*
X400000D03*
Y1820000D03*
X380000D03*
X360000D03*
X340000D03*
X360000Y1800000D03*
X400000D03*
X380000D03*
X400000Y1940000D03*
X380000D03*
X360000D03*
X340000D03*
Y1900000D03*
Y1920000D03*
X360000D03*
Y1900000D03*
X380000D03*
Y1920000D03*
X400000D03*
Y1900000D03*
X340000Y1880000D03*
X360000D03*
X380000D03*
X400000D03*
X340000Y1980000D03*
Y1960000D03*
X360000Y1980000D03*
Y1960000D03*
X380000Y1980000D03*
Y1960000D03*
X400000Y1980000D03*
Y1960000D03*
X392559Y1986626D03*
X372559D03*
X352559D03*
X332559D03*
X460000Y20000D03*
Y40000D03*
X420000Y20000D03*
Y40000D03*
X440000D03*
Y20000D03*
X470018Y5500D03*
X410018D03*
X430018D03*
X450018D03*
X460000Y100000D03*
X420000D03*
X440000D03*
X460000Y80000D03*
Y60000D03*
X440000D03*
Y80000D03*
X420000D03*
Y60000D03*
X460000Y120000D03*
X440000D03*
X420000D03*
Y180000D03*
X440000D03*
X460000D03*
Y140000D03*
Y160000D03*
X440000D03*
Y140000D03*
X420000D03*
Y160000D03*
Y200000D03*
X460000D03*
X440000D03*
X420000Y220000D03*
X440000D03*
X460000D03*
Y240000D03*
X440000D03*
X420000D03*
Y260000D03*
X440000D03*
X460000D03*
X440000Y280000D03*
X460000D03*
X440000Y320000D03*
X460000D03*
Y300000D03*
X440000Y400000D03*
X460000D03*
Y380000D03*
X440000D03*
Y360000D03*
X460000D03*
Y340000D03*
X440000D03*
X460000Y480000D03*
Y460000D03*
X440000Y480000D03*
Y460000D03*
Y440000D03*
X460000D03*
Y420000D03*
X440000D03*
X420000Y520000D03*
Y540000D03*
X440000D03*
Y520000D03*
X460000D03*
Y500000D03*
X420000D03*
Y620000D03*
X440000Y600000D03*
X460000Y580000D03*
X420000Y600000D03*
X440000Y580000D03*
X420000Y560000D03*
Y700000D03*
X460000Y660000D03*
Y680000D03*
Y700000D03*
X420000Y680000D03*
Y660000D03*
Y720000D03*
Y740000D03*
X460000Y720000D03*
Y760000D03*
X420000D03*
Y840000D03*
X440000D03*
X460000D03*
Y820000D03*
Y800000D03*
Y780000D03*
X420000D03*
Y920000D03*
X440000D03*
X460000D03*
Y900000D03*
X440000D03*
X420000D03*
Y880000D03*
X460000D03*
X440000D03*
X420000Y860000D03*
X440000D03*
X460000D03*
X420000Y980000D03*
X440000D03*
X460000D03*
Y960000D03*
X440000D03*
X420000D03*
Y940000D03*
X440000D03*
X460000D03*
X420000Y1060000D03*
X440000Y1040000D03*
X420000D03*
Y1000000D03*
Y1020000D03*
X440000Y1000000D03*
Y1020000D03*
X460000D03*
Y1000000D03*
X440000Y1120000D03*
X460000D03*
Y1080000D03*
X420000Y1200000D03*
X440000D03*
X460000D03*
Y1160000D03*
Y1180000D03*
X440000Y1160000D03*
Y1180000D03*
X420000Y1160000D03*
Y1180000D03*
Y1280000D03*
Y1240000D03*
X440000D03*
X460000D03*
Y1260000D03*
X440000D03*
X420000D03*
X460000Y1280000D03*
X440000D03*
X420000Y1340000D03*
Y1320000D03*
X440000D03*
Y1340000D03*
X460000D03*
Y1320000D03*
X440000Y1300000D03*
X420000D03*
X460000D03*
X440000Y1420000D03*
X420000D03*
Y1400000D03*
Y1380000D03*
Y1360000D03*
X440000Y1400000D03*
Y1360000D03*
Y1380000D03*
X460000D03*
Y1360000D03*
Y1420000D03*
Y1400000D03*
X440000Y1500000D03*
X420000Y1480000D03*
X440000D03*
Y1460000D03*
X420000D03*
Y1440000D03*
X440000D03*
X460000Y1500000D03*
Y1480000D03*
Y1460000D03*
Y1440000D03*
X420000Y1540000D03*
X460000Y1520000D03*
Y1580000D03*
X440000D03*
X420000D03*
Y1700000D03*
Y1680000D03*
Y1660000D03*
X440000Y1680000D03*
X460000D03*
Y1660000D03*
X420000Y1760000D03*
X406500Y1736500D03*
X440000Y1780000D03*
Y1760000D03*
X460000D03*
Y1780000D03*
X450000Y1803500D03*
X440000Y1860000D03*
X420000D03*
Y1840000D03*
X440000D03*
X420000Y1820000D03*
X460000Y1840000D03*
Y1860000D03*
Y1940000D03*
X440000D03*
X420000D03*
Y1900000D03*
Y1920000D03*
X440000D03*
Y1900000D03*
X460000Y1920000D03*
Y1900000D03*
X420000Y1880000D03*
X440000D03*
X460000D03*
X420000Y1980000D03*
Y1960000D03*
X440000Y1980000D03*
Y1960000D03*
X460000Y1980000D03*
Y1960000D03*
X472559Y1986626D03*
X452559D03*
X432559D03*
X412559D03*
X500000Y40000D03*
X480000D03*
X520000D03*
X530018Y5500D03*
X510018D03*
X490018D03*
X500000Y20000D03*
X480000D03*
X520000D03*
X540000Y40000D03*
Y20000D03*
Y100000D03*
X520000D03*
X500000D03*
X480000D03*
Y120000D03*
X500000D03*
X520000D03*
X480000Y60000D03*
Y80000D03*
X500000D03*
Y60000D03*
X520000D03*
Y80000D03*
X540000Y120000D03*
Y80000D03*
Y60000D03*
X480000Y140000D03*
Y160000D03*
X500000D03*
Y140000D03*
X520000D03*
Y160000D03*
Y180000D03*
X500000D03*
X480000D03*
X540000Y160000D03*
Y140000D03*
Y180000D03*
X520000Y260000D03*
X500000D03*
X520000Y240000D03*
X480000D03*
X500000D03*
Y220000D03*
X480000D03*
Y200000D03*
X500000D03*
X520000D03*
Y220000D03*
X540000Y260000D03*
Y220000D03*
Y240000D03*
Y200000D03*
X500000Y280000D03*
X520000D03*
X480000D03*
Y300000D03*
X500000D03*
X520000D03*
Y320000D03*
X500000D03*
X480000D03*
X540000Y280000D03*
Y300000D03*
Y320000D03*
X500000Y400000D03*
X520000D03*
Y380000D03*
X540000Y400000D03*
Y380000D03*
Y360000D03*
Y340000D03*
X480000Y400000D03*
Y340000D03*
X500000D03*
X520000D03*
Y360000D03*
X500000D03*
X480000D03*
Y380000D03*
Y440000D03*
X500000D03*
X480000Y420000D03*
X500000D03*
X520000D03*
X540000D03*
X520000Y480000D03*
X500000D03*
X480000D03*
Y460000D03*
X500000D03*
X520000D03*
Y440000D03*
X540000Y460000D03*
Y440000D03*
X500000Y500000D03*
X480000D03*
X520000Y520000D03*
X500000Y540000D03*
X540000D03*
X520000Y560000D03*
X540000D03*
Y580000D03*
X500000D03*
Y600000D03*
X520000D03*
X540000D03*
X520000Y580000D03*
X480000Y560000D03*
X540000Y700000D03*
X520000D03*
X500000D03*
X480000D03*
X540000Y680000D03*
X520000D03*
X500000D03*
X480000D03*
X540000Y660000D03*
X520000D03*
X500000D03*
X480000D03*
Y640000D03*
X500000D03*
X520000D03*
X540000D03*
X520000Y720000D03*
X500000D03*
X480000D03*
X540000Y740000D03*
X480000Y760000D03*
X500000D03*
X520000D03*
X540000D03*
X520000Y780000D03*
X500000D03*
X480000D03*
Y800000D03*
X500000D03*
X520000D03*
X480000Y820000D03*
X500000D03*
X520000D03*
X480000Y840000D03*
X500000D03*
X520000D03*
X540000D03*
Y780000D03*
Y800000D03*
Y820000D03*
X520000Y900000D03*
Y920000D03*
X500000D03*
X480000D03*
X520000Y860000D03*
X500000D03*
X480000D03*
Y880000D03*
X500000D03*
X520000D03*
X480000Y900000D03*
X500000D03*
X540000Y920000D03*
Y860000D03*
Y880000D03*
Y900000D03*
X520000Y980000D03*
X500000D03*
X480000D03*
X520000Y940000D03*
X500000D03*
X480000D03*
Y960000D03*
X500000D03*
X520000D03*
X540000Y980000D03*
Y940000D03*
Y960000D03*
X520000Y1060000D03*
X500000D03*
X480000D03*
Y1000000D03*
X500000Y1040000D03*
X520000D03*
X540000Y1060000D03*
Y1040000D03*
X480000Y1080000D03*
X500000D03*
X520000D03*
Y1120000D03*
X500000D03*
X480000D03*
X540000D03*
Y1100000D03*
X520000Y1200000D03*
X500000D03*
X480000D03*
Y1180000D03*
Y1160000D03*
X500000Y1180000D03*
Y1160000D03*
X520000Y1180000D03*
Y1160000D03*
X540000Y1180000D03*
Y1160000D03*
Y1200000D03*
X480000Y1280000D03*
X500000D03*
X520000D03*
X480000Y1260000D03*
X500000D03*
X520000D03*
X500000Y1240000D03*
X480000D03*
X540000Y1280000D03*
Y1220000D03*
X500000Y1340000D03*
X520000D03*
X480000D03*
Y1320000D03*
X500000D03*
X520000D03*
X480000Y1300000D03*
X500000D03*
X520000D03*
X540000Y1340000D03*
Y1320000D03*
Y1300000D03*
X520000Y1420000D03*
X500000D03*
X480000D03*
X520000Y1380000D03*
Y1400000D03*
X500000Y1380000D03*
Y1400000D03*
X480000Y1380000D03*
Y1400000D03*
X500000Y1360000D03*
X520000D03*
X480000D03*
X540000Y1420000D03*
Y1380000D03*
Y1400000D03*
Y1360000D03*
X520000Y1500000D03*
X500000D03*
X480000D03*
X520000Y1440000D03*
Y1460000D03*
Y1480000D03*
X500000Y1440000D03*
Y1460000D03*
Y1480000D03*
X480000Y1440000D03*
Y1460000D03*
Y1480000D03*
X540000Y1500000D03*
Y1440000D03*
Y1460000D03*
Y1480000D03*
X500000Y1560000D03*
X480000Y1520000D03*
X500000D03*
X520000D03*
X540000D03*
X480000Y1580000D03*
X540000Y1680000D03*
X520000D03*
X500000D03*
X480000D03*
Y1700000D03*
Y1660000D03*
Y1720000D03*
X500000D03*
X520000D03*
Y1700000D03*
X500000D03*
X520000Y1660000D03*
X500000D03*
X540000Y1700000D03*
Y1720000D03*
Y1660000D03*
Y1780000D03*
X520000Y1760000D03*
X480000Y1780000D03*
X500000D03*
X520000D03*
X480000Y1760000D03*
X500000D03*
X520000Y1740000D03*
X500000D03*
X480000D03*
X540000Y1760000D03*
Y1740000D03*
Y1820000D03*
Y1840000D03*
Y1860000D03*
X520000D03*
X480000D03*
X500000Y1840000D03*
X520000D03*
X500000Y1820000D03*
X480000D03*
X520000D03*
X540000Y1940000D03*
X500000D03*
X520000D03*
X480000D03*
X520000Y1920000D03*
X500000D03*
X480000D03*
X520000Y1900000D03*
X500000D03*
X480000D03*
Y1880000D03*
X500000D03*
X520000D03*
X540000Y1900000D03*
Y1880000D03*
Y1920000D03*
X492559Y1986626D03*
X512559D03*
X532559D03*
X520000Y1960000D03*
Y1980000D03*
X500000Y1960000D03*
Y1980000D03*
X480000Y1960000D03*
Y1980000D03*
X540000Y1960000D03*
Y1980000D03*
X580000Y40000D03*
X560000D03*
X600000D03*
X590018Y5500D03*
X570018D03*
X550018D03*
X580000Y20000D03*
X560000D03*
X600000D03*
X620000Y40000D03*
X610018Y5500D03*
X620000Y20000D03*
Y100000D03*
X600000D03*
X580000D03*
X560000D03*
Y120000D03*
X580000D03*
X600000D03*
X560000Y60000D03*
Y80000D03*
X580000D03*
Y60000D03*
X600000D03*
Y80000D03*
X620000Y120000D03*
Y80000D03*
Y60000D03*
X560000Y140000D03*
Y160000D03*
X580000D03*
Y140000D03*
X600000D03*
Y160000D03*
Y180000D03*
X580000D03*
X560000D03*
X620000Y160000D03*
Y140000D03*
Y180000D03*
X580000Y260000D03*
X600000D03*
X620000D03*
X560000D03*
X600000Y200000D03*
Y220000D03*
X580000D03*
Y200000D03*
X560000D03*
Y220000D03*
Y240000D03*
X580000D03*
X600000D03*
X620000D03*
Y220000D03*
Y200000D03*
X560000Y320000D03*
X580000D03*
X600000D03*
X620000D03*
X560000Y300000D03*
X580000D03*
X600000D03*
X620000D03*
X580000Y280000D03*
X600000D03*
X620000D03*
X560000D03*
X620000Y400000D03*
X600000D03*
X580000D03*
X560000D03*
Y380000D03*
X580000D03*
X600000D03*
X620000D03*
X560000Y360000D03*
X580000D03*
X600000D03*
X620000D03*
X560000Y340000D03*
X580000D03*
X600000D03*
X620000D03*
X600000Y480000D03*
X620000D03*
Y460000D03*
X580000Y440000D03*
X560000D03*
X620000Y420000D03*
X600000D03*
X580000D03*
X560000D03*
Y460000D03*
X620000Y520000D03*
X600000D03*
X580000D03*
Y500000D03*
X600000Y540000D03*
Y500000D03*
X620000D03*
X580000Y540000D03*
X560000D03*
X620000D03*
Y560000D03*
X580000D03*
X600000D03*
X560000D03*
Y580000D03*
X600000D03*
X620000Y600000D03*
X600000D03*
X580000D03*
Y580000D03*
X620000D03*
Y640000D03*
X600000D03*
X580000D03*
X560000D03*
X620000Y700000D03*
X600000D03*
X580000D03*
X560000D03*
X620000Y680000D03*
X600000D03*
X580000D03*
X560000D03*
X620000Y660000D03*
X600000D03*
X580000D03*
X560000D03*
Y740000D03*
X580000D03*
X600000D03*
X620000D03*
X580000Y760000D03*
X600000D03*
X620000D03*
X560000D03*
X580000Y780000D03*
X600000D03*
X620000D03*
X580000Y800000D03*
X600000D03*
X620000D03*
X580000Y820000D03*
X600000D03*
X620000D03*
X560000Y840000D03*
X580000D03*
X600000D03*
X560000Y780000D03*
Y800000D03*
X620000Y840000D03*
X600000Y920000D03*
X580000D03*
X560000D03*
X600000Y860000D03*
X580000D03*
X560000D03*
Y900000D03*
Y880000D03*
X580000D03*
Y900000D03*
X600000D03*
Y880000D03*
X620000Y920000D03*
Y880000D03*
Y900000D03*
Y860000D03*
X600000Y980000D03*
X580000D03*
X560000D03*
X580000Y940000D03*
X560000D03*
Y960000D03*
X580000D03*
X600000D03*
Y940000D03*
X620000D03*
Y960000D03*
Y980000D03*
X600000Y1060000D03*
X580000D03*
X560000D03*
Y1040000D03*
X580000D03*
X600000D03*
X620000D03*
Y1060000D03*
X560000Y1100000D03*
X580000D03*
X600000D03*
Y1120000D03*
X580000D03*
X560000D03*
X620000D03*
Y1100000D03*
X560000Y1180000D03*
X580000D03*
Y1160000D03*
X600000Y1180000D03*
Y1160000D03*
Y1200000D03*
X580000D03*
X560000D03*
X620000D03*
Y1160000D03*
Y1180000D03*
X580000Y1260000D03*
Y1240000D03*
X560000D03*
X600000Y1220000D03*
X580000D03*
X560000D03*
X600000Y1260000D03*
Y1240000D03*
X620000Y1280000D03*
Y1220000D03*
Y1240000D03*
Y1260000D03*
X560000Y1340000D03*
X580000D03*
X600000D03*
X560000Y1320000D03*
X580000D03*
X560000Y1300000D03*
X620000D03*
X600000Y1420000D03*
X580000D03*
X560000D03*
X600000Y1400000D03*
X580000Y1380000D03*
Y1400000D03*
X560000Y1380000D03*
Y1400000D03*
X580000Y1360000D03*
X600000D03*
X620000Y1420000D03*
Y1400000D03*
Y1380000D03*
Y1360000D03*
X600000Y1500000D03*
X580000D03*
X560000D03*
X600000Y1440000D03*
Y1460000D03*
Y1480000D03*
X580000Y1440000D03*
Y1460000D03*
Y1480000D03*
X560000Y1440000D03*
Y1460000D03*
Y1480000D03*
X620000Y1500000D03*
Y1480000D03*
Y1460000D03*
Y1440000D03*
X560000Y1520000D03*
X580000D03*
X620000Y1680000D03*
X560000D03*
X580000D03*
X600000D03*
Y1700000D03*
Y1720000D03*
X580000D03*
Y1700000D03*
X560000D03*
Y1720000D03*
X600000Y1660000D03*
X580000D03*
X560000D03*
X620000Y1700000D03*
Y1720000D03*
Y1660000D03*
Y1780000D03*
X600000D03*
X580000D03*
X560000D03*
X620000Y1760000D03*
X600000D03*
X580000D03*
X560000D03*
X620000Y1740000D03*
X600000D03*
X580000D03*
X560000D03*
Y1840000D03*
Y1860000D03*
X620000Y1800000D03*
X600000D03*
X580000D03*
X560000D03*
X620000Y1840000D03*
X600000D03*
X580000D03*
X620000Y1860000D03*
X600000D03*
X580000D03*
X560000Y1940000D03*
X580000D03*
X600000D03*
X620000D03*
X560000Y1880000D03*
X620000D03*
X600000D03*
X580000D03*
X620000Y1900000D03*
X600000D03*
X580000D03*
X620000Y1920000D03*
X600000D03*
X580000D03*
X560000D03*
Y1900000D03*
X620000Y1960000D03*
X600000D03*
X580000D03*
X552559Y1986626D03*
X572559D03*
X592559D03*
X600000Y1980000D03*
X580000D03*
X560000D03*
Y1960000D03*
X612559Y1986626D03*
X620000Y1980000D03*
X660000Y40000D03*
X640000D03*
X670018Y5500D03*
X650018D03*
X630018D03*
X660000Y20000D03*
X640000D03*
X680000D03*
Y40000D03*
X690018Y5500D03*
X680000Y100000D03*
X660000D03*
X640000D03*
Y120000D03*
X660000D03*
X640000Y60000D03*
Y80000D03*
X660000D03*
Y60000D03*
X680000Y120000D03*
Y60000D03*
Y80000D03*
X640000Y140000D03*
Y160000D03*
X660000D03*
Y140000D03*
Y180000D03*
X640000D03*
X680000Y140000D03*
Y160000D03*
Y180000D03*
X660000Y260000D03*
X640000D03*
Y240000D03*
X660000D03*
Y220000D03*
Y200000D03*
X640000Y220000D03*
Y200000D03*
X680000Y260000D03*
Y240000D03*
Y220000D03*
Y200000D03*
X640000Y320000D03*
X660000D03*
X680000D03*
X640000Y300000D03*
X660000D03*
X680000D03*
X640000Y280000D03*
X660000D03*
X680000D03*
X640000Y400000D03*
Y380000D03*
X660000D03*
X640000Y360000D03*
X660000D03*
X680000D03*
X640000Y340000D03*
X660000D03*
X680000D03*
Y480000D03*
Y460000D03*
Y440000D03*
X640000Y480000D03*
X660000D03*
Y460000D03*
X640000D03*
X660000Y440000D03*
X640000D03*
X680000Y420000D03*
X660000Y520000D03*
X640000D03*
X680000D03*
Y500000D03*
X640000D03*
X660000D03*
X640000Y540000D03*
X660000D03*
X680000D03*
Y560000D03*
X660000D03*
X640000D03*
X680000Y600000D03*
X660000D03*
X640000D03*
Y580000D03*
X660000D03*
X680000D03*
Y660000D03*
Y680000D03*
X640000Y640000D03*
Y700000D03*
X660000Y680000D03*
X640000D03*
X660000Y660000D03*
X640000D03*
X660000Y640000D03*
X680000D03*
X640000Y720000D03*
X660000D03*
X680000D03*
X640000Y740000D03*
X660000D03*
X680000D03*
X640000Y760000D03*
X660000D03*
X680000D03*
X640000Y780000D03*
X660000D03*
X680000D03*
X640000Y800000D03*
X660000D03*
X680000D03*
X640000Y820000D03*
X660000D03*
X680000D03*
X640000Y840000D03*
X660000D03*
X680000D03*
X640000Y920000D03*
X660000D03*
X640000Y900000D03*
X660000D03*
X640000Y880000D03*
X660000D03*
X640000Y860000D03*
X660000D03*
X680000Y920000D03*
Y900000D03*
Y880000D03*
Y860000D03*
X640000Y940000D03*
Y960000D03*
X660000D03*
Y980000D03*
X640000D03*
X680000D03*
Y960000D03*
X660000Y1040000D03*
X640000D03*
Y1060000D03*
X680000Y1040000D03*
X640000Y1100000D03*
Y1120000D03*
X660000D03*
Y1100000D03*
X680000D03*
Y1120000D03*
Y1080000D03*
X640000Y1200000D03*
X660000D03*
Y1160000D03*
X640000D03*
Y1180000D03*
X680000Y1160000D03*
Y1200000D03*
X640000Y1280000D03*
X660000D03*
Y1220000D03*
X640000D03*
Y1240000D03*
X660000D03*
X640000Y1260000D03*
X660000D03*
X680000Y1240000D03*
Y1260000D03*
Y1280000D03*
Y1220000D03*
X660000Y1340000D03*
X640000Y1300000D03*
X660000D03*
Y1320000D03*
X640000D03*
X680000Y1340000D03*
Y1300000D03*
Y1320000D03*
X660000Y1420000D03*
X640000D03*
Y1400000D03*
X660000D03*
X640000Y1380000D03*
X680000Y1420000D03*
Y1360000D03*
X660000Y1500000D03*
X640000D03*
X660000Y1480000D03*
X640000D03*
Y1460000D03*
Y1440000D03*
X660000D03*
X680000Y1500000D03*
Y1480000D03*
Y1440000D03*
X640000Y1680000D03*
X660000D03*
X680000D03*
Y1720000D03*
X640000Y1700000D03*
X660000D03*
Y1720000D03*
X640000D03*
Y1660000D03*
X660000D03*
X680000Y1780000D03*
X660000D03*
X640000D03*
X680000Y1760000D03*
X660000D03*
X640000D03*
X680000Y1740000D03*
X660000D03*
X640000D03*
X680000Y1820000D03*
X660000D03*
X680000Y1800000D03*
X660000D03*
X640000D03*
X680000Y1860000D03*
X660000Y1840000D03*
X640000D03*
Y1860000D03*
X660000D03*
X680000Y1880000D03*
Y1900000D03*
Y1920000D03*
X660000Y1880000D03*
X640000D03*
X660000Y1900000D03*
X640000D03*
X660000Y1920000D03*
X640000D03*
Y1940000D03*
X660000D03*
X680000Y1960000D03*
X660000D03*
X640000D03*
X632559Y1986626D03*
X652559D03*
X672559D03*
X660000Y1980000D03*
X640000D03*
X680000D03*
X692559Y1986626D03*
X700000Y20000D03*
X740000Y40000D03*
X750018Y5500D03*
X730018D03*
X710018D03*
X740000Y20000D03*
X720000D03*
X760000Y40000D03*
Y20000D03*
X700000Y120000D03*
X720000D03*
X740000D03*
X700000Y80000D03*
Y60000D03*
Y100000D03*
X720000D03*
Y60000D03*
X740000D03*
Y80000D03*
X720000D03*
X740000Y100000D03*
X760000Y120000D03*
Y100000D03*
Y80000D03*
Y60000D03*
X700000Y180000D03*
X740000D03*
X720000D03*
Y140000D03*
Y160000D03*
X760000D03*
X740000D03*
X700000D03*
Y140000D03*
X740000D03*
X760000D03*
Y180000D03*
X700000Y260000D03*
Y240000D03*
Y220000D03*
Y200000D03*
X720000Y260000D03*
Y240000D03*
Y220000D03*
Y200000D03*
X740000Y260000D03*
Y200000D03*
Y220000D03*
Y240000D03*
X760000Y260000D03*
Y200000D03*
Y220000D03*
Y240000D03*
Y320000D03*
X700000D03*
Y300000D03*
Y280000D03*
X720000Y320000D03*
Y300000D03*
Y280000D03*
X740000D03*
Y300000D03*
X760000Y280000D03*
X740000Y400000D03*
X720000D03*
X700000D03*
X740000Y380000D03*
X720000D03*
X760000Y400000D03*
Y360000D03*
Y380000D03*
Y460000D03*
Y480000D03*
X740000D03*
X720000D03*
X700000D03*
Y420000D03*
X720000D03*
X740000D03*
Y440000D03*
X720000D03*
X700000D03*
Y460000D03*
X720000D03*
X740000D03*
X760000Y420000D03*
Y440000D03*
X720000Y520000D03*
X700000D03*
X740000Y500000D03*
X720000D03*
X740000Y520000D03*
X700000Y500000D03*
Y540000D03*
X740000D03*
X720000D03*
X760000D03*
Y520000D03*
Y500000D03*
Y560000D03*
X720000D03*
X740000D03*
X700000D03*
X740000Y600000D03*
Y580000D03*
X720000D03*
X740000Y620000D03*
X720000D03*
X700000Y580000D03*
Y600000D03*
X720000D03*
X760000Y620000D03*
Y600000D03*
Y580000D03*
Y680000D03*
Y640000D03*
X740000D03*
Y680000D03*
X720000D03*
X700000D03*
Y660000D03*
X720000D03*
X740000D03*
X700000Y640000D03*
X720000D03*
X700000Y720000D03*
X720000D03*
X740000D03*
Y760000D03*
X720000D03*
X700000D03*
Y740000D03*
X720000D03*
X740000D03*
X760000Y760000D03*
Y740000D03*
Y720000D03*
X740000Y840000D03*
X700000D03*
X720000D03*
X740000Y800000D03*
X720000D03*
X700000D03*
Y820000D03*
X720000D03*
X740000D03*
X700000Y780000D03*
X720000D03*
X740000D03*
X760000Y840000D03*
Y800000D03*
Y820000D03*
Y780000D03*
X740000Y920000D03*
X700000D03*
X720000D03*
X740000Y900000D03*
Y880000D03*
Y860000D03*
X700000Y900000D03*
X720000D03*
X700000Y880000D03*
X720000D03*
X700000Y860000D03*
X720000D03*
X760000Y920000D03*
Y900000D03*
Y880000D03*
Y860000D03*
X700000Y980000D03*
X720000D03*
X740000D03*
X700000Y960000D03*
X720000D03*
X740000D03*
X760000Y980000D03*
Y960000D03*
X740000Y1040000D03*
X720000D03*
X700000D03*
X760000D03*
X700000Y1120000D03*
Y1100000D03*
X720000Y1120000D03*
X740000D03*
Y1080000D03*
X700000D03*
X760000Y1120000D03*
X740000Y1160000D03*
X720000D03*
X700000D03*
Y1200000D03*
X720000D03*
X740000D03*
X760000Y1160000D03*
Y1200000D03*
X700000Y1240000D03*
X740000Y1260000D03*
X720000D03*
X700000D03*
X740000Y1280000D03*
X720000D03*
X700000D03*
Y1220000D03*
X720000D03*
X740000D03*
Y1240000D03*
X720000D03*
X760000D03*
Y1260000D03*
Y1280000D03*
Y1220000D03*
X740000Y1340000D03*
X720000D03*
X700000D03*
X740000Y1300000D03*
X720000D03*
X700000D03*
Y1320000D03*
X740000D03*
X720000D03*
X760000Y1340000D03*
Y1300000D03*
Y1320000D03*
X740000Y1420000D03*
X720000D03*
X740000Y1380000D03*
Y1360000D03*
X720000Y1380000D03*
Y1360000D03*
X700000Y1380000D03*
Y1360000D03*
X760000Y1420000D03*
Y1380000D03*
Y1360000D03*
X700000Y1500000D03*
X740000Y1440000D03*
X720000D03*
X700000D03*
X740000Y1480000D03*
X720000D03*
X700000D03*
X760000Y1440000D03*
Y1480000D03*
X740000Y1520000D03*
X720000D03*
X760000D03*
X700000Y1680000D03*
X740000Y1700000D03*
X720000D03*
Y1720000D03*
X740000D03*
Y1680000D03*
X720000D03*
X760000Y1720000D03*
X700000Y1780000D03*
Y1760000D03*
Y1740000D03*
X720000Y1780000D03*
X740000Y1740000D03*
X760000Y1780000D03*
Y1740000D03*
X758000Y1756000D03*
X759700Y1817500D03*
X700000Y1820000D03*
Y1800000D03*
Y1860000D03*
X720000D03*
X740000D03*
X720000Y1800000D03*
X740000D03*
Y1820000D03*
X720000D03*
X759700Y1837500D03*
X720000Y1880000D03*
X740000Y1900000D03*
Y1880000D03*
X700000D03*
Y1900000D03*
Y1920000D03*
X720000Y1940000D03*
Y1900000D03*
Y1920000D03*
X700000Y1940000D03*
X760000Y1880000D03*
Y1940000D03*
X720000Y1960000D03*
X700000D03*
X720000Y1980000D03*
X700000D03*
X712559Y1986626D03*
X732559D03*
X740000Y1960000D03*
Y1980000D03*
X752559Y1986626D03*
X759900Y1959200D03*
X760000Y1980000D03*
X800000Y40000D03*
X820000D03*
X840000D03*
X780000D03*
X810018Y5500D03*
X790018D03*
X770018D03*
X780000Y20000D03*
X800000D03*
X820000D03*
X830018Y5500D03*
X840000Y20000D03*
X800000Y120000D03*
X820000D03*
X840000D03*
X800000Y100000D03*
X820000D03*
X840000D03*
X800000Y80000D03*
X820000D03*
X840000D03*
X800000Y60000D03*
X820000D03*
X840000D03*
X780000Y120000D03*
Y60000D03*
Y80000D03*
Y100000D03*
Y160000D03*
X840000Y140000D03*
X820000D03*
X800000D03*
X816000Y187000D03*
X780000Y140000D03*
Y180000D03*
X828500Y171000D03*
X840000Y174250D03*
X820500Y171000D03*
X820000Y260000D03*
X780000Y200000D03*
Y220000D03*
Y240000D03*
X800000Y220000D03*
Y240000D03*
X820000Y220000D03*
X840000Y240000D03*
X828000Y203000D03*
X780000Y300000D03*
X800000Y280000D03*
Y340000D03*
X780000D03*
Y380000D03*
Y360000D03*
Y400000D03*
X820000D03*
X800000D03*
Y380000D03*
Y360000D03*
X840000Y400000D03*
X780000Y440000D03*
Y420000D03*
Y460000D03*
X800000Y480000D03*
X820000Y420000D03*
Y440000D03*
Y460000D03*
X800000D03*
Y440000D03*
Y420000D03*
X820000Y480000D03*
X780000D03*
X840000D03*
Y420000D03*
Y440000D03*
Y460000D03*
X780000Y540000D03*
X800000D03*
X820000D03*
X780000Y500000D03*
X820000D03*
Y520000D03*
X800000Y500000D03*
Y520000D03*
X780000D03*
X840000Y500000D03*
Y520000D03*
Y540000D03*
X780000Y580000D03*
Y560000D03*
X800000Y600000D03*
Y580000D03*
Y560000D03*
X780000Y620000D03*
X800000D03*
X820000D03*
X780000Y600000D03*
X820000Y580000D03*
Y560000D03*
Y600000D03*
X840000Y620000D03*
Y580000D03*
Y560000D03*
Y600000D03*
X820000Y700000D03*
X780000D03*
X778400Y659800D03*
X800000Y640000D03*
X780000D03*
X820000Y660000D03*
X798400Y659800D03*
X840000Y640000D03*
Y680000D03*
Y660000D03*
Y700000D03*
X820000Y720000D03*
X800000Y760000D03*
X780000D03*
Y740000D03*
X800000D03*
Y720000D03*
X780000D03*
X840000D03*
X780000Y840000D03*
X800000D03*
X820000D03*
Y820000D03*
X780000Y800000D03*
Y780000D03*
X800000D03*
X840000Y840000D03*
Y800000D03*
Y820000D03*
X780000Y920000D03*
X800000D03*
X820000D03*
X780000Y900000D03*
X800000D03*
X820000D03*
X780000Y880000D03*
X800000D03*
X820000D03*
X780000Y860000D03*
X800000D03*
X820000D03*
X840000Y920000D03*
Y860000D03*
Y880000D03*
Y900000D03*
X780000Y980000D03*
X800000D03*
X820000D03*
X780000Y960000D03*
X800000D03*
X820000D03*
X840000D03*
Y980000D03*
X800000Y1060000D03*
X820000D03*
X780000D03*
X820000Y1040000D03*
X840000Y1060000D03*
Y1040000D03*
X780000Y1120000D03*
X800000D03*
Y1080000D03*
Y1100000D03*
X820000Y1120000D03*
X800000Y1200000D03*
X820000D03*
X780000Y1160000D03*
X800000D03*
X780000Y1200000D03*
X840000D03*
X820000Y1220000D03*
Y1240000D03*
X800000D03*
X780000D03*
X820000Y1260000D03*
X800000D03*
X780000D03*
X820000Y1280000D03*
X800000D03*
X780000D03*
Y1220000D03*
X800000D03*
X840000Y1280000D03*
Y1220000D03*
Y1240000D03*
Y1260000D03*
X820000Y1340000D03*
X800000D03*
X780000D03*
X820000Y1300000D03*
X800000D03*
X780000D03*
Y1320000D03*
X820000D03*
X800000D03*
X840000Y1340000D03*
Y1300000D03*
Y1320000D03*
X820000Y1420000D03*
X800000D03*
X780000D03*
X820000Y1380000D03*
Y1360000D03*
X800000Y1380000D03*
Y1360000D03*
X780000Y1380000D03*
Y1360000D03*
X840000Y1420000D03*
Y1360000D03*
Y1380000D03*
X820000Y1440000D03*
X800000D03*
X780000D03*
X820000Y1480000D03*
X800000D03*
X780000D03*
X840000Y1440000D03*
Y1480000D03*
X800000Y1560000D03*
X780000Y1520000D03*
X840000Y1640000D03*
Y1600000D03*
X820000Y1680000D03*
X840000D03*
Y1660000D03*
X780000Y1780000D03*
X800000D03*
Y1740000D03*
X780000D03*
X795500Y1755000D03*
X837500Y1785000D03*
X829500D03*
X819000D03*
X816000Y1801000D03*
X780000Y1800000D03*
X800000D03*
X780000Y1840000D03*
X800000Y1820000D03*
X820000D03*
X828000Y1862000D03*
X827500Y1817000D03*
X800000Y1920000D03*
X820000D03*
X780000D03*
X820000Y1980000D03*
X772559Y1986626D03*
X792559D03*
X812559D03*
X769239Y1955776D03*
X780000Y1980000D03*
X800000D03*
X823400Y1973400D03*
X827900D03*
X835900Y1973500D03*
X839400D03*
X832559Y1986626D03*
X840000Y1980000D03*
X799205Y1960532D03*
X860000Y40000D03*
X880000D03*
X890018Y5500D03*
X870018D03*
X850018D03*
X880000Y20000D03*
X860000D03*
X900000Y40000D03*
X910018Y5500D03*
X900000Y20000D03*
X860000Y120000D03*
X880000D03*
X860000Y100000D03*
X880000D03*
X860000Y80000D03*
X880000D03*
X860000Y60000D03*
X880000D03*
X900000Y120000D03*
Y60000D03*
Y100000D03*
Y80000D03*
X860000Y140000D03*
X908493Y136513D03*
X880000Y180000D03*
X869250Y144750D03*
X885993Y134893D03*
X860000Y260000D03*
Y240000D03*
X908654Y231105D03*
X904838D03*
X872500Y241500D03*
X860100Y336500D03*
X873600Y332200D03*
X860100Y333000D03*
X901500Y312500D03*
X856200Y337300D03*
X865000Y371000D03*
X868500D03*
X876000D03*
X872500D03*
X879600Y385200D03*
X860000Y400000D03*
X880000D03*
X900000D03*
X899900Y382300D03*
X850966Y370025D03*
X880000Y480000D03*
X860000D03*
X880000Y420000D03*
X860000D03*
X880000Y440000D03*
X860000D03*
X880000Y460000D03*
X860000D03*
X900000Y480000D03*
Y420000D03*
Y440000D03*
Y460000D03*
X907493Y542025D03*
X880000Y500000D03*
X860000D03*
X880000Y520000D03*
X860000D03*
X900000Y500000D03*
Y520000D03*
X872875Y535275D03*
X891250Y537500D03*
X860000Y580000D03*
Y560000D03*
X880000Y580000D03*
Y600000D03*
X860000D03*
X900000D03*
X908654Y636613D03*
X904838D03*
X868500Y654000D03*
X859500Y741800D03*
X873400Y738400D03*
X859500Y738300D03*
X901500Y718000D03*
X856100Y743300D03*
X850966Y775525D03*
X860000Y840000D03*
X880000D03*
X864500Y776500D03*
X868000D03*
X872000D03*
X875500D03*
X860000Y800000D03*
X880000D03*
X860000Y820000D03*
X880000D03*
X900000Y840000D03*
Y800000D03*
Y820000D03*
X860000Y920000D03*
X880000D03*
X860000Y860000D03*
X880000D03*
X860000Y880000D03*
X880000D03*
X860000Y900000D03*
X880000D03*
X900000Y920000D03*
Y860000D03*
Y880000D03*
Y900000D03*
X907493Y947537D03*
X860000Y980000D03*
X886517Y945917D03*
X872875Y940925D03*
X880000Y1000000D03*
X860000Y1040000D03*
X908654Y1042129D03*
X904838D03*
X900000Y1000000D03*
Y1040000D03*
Y1020000D03*
X868500Y1059500D03*
X900000Y1080000D03*
X901500Y1123500D03*
X859500Y1147600D03*
X874200Y1144000D03*
X859500Y1144100D03*
X864000Y1181900D03*
X867500D03*
X872200D03*
X875700D03*
X860000Y1200000D03*
X880000D03*
X900000D03*
X854500Y1148700D03*
X850600Y1181025D03*
X860000Y1280000D03*
X880000D03*
X860000Y1220000D03*
Y1240000D03*
Y1260000D03*
X880000Y1220000D03*
Y1240000D03*
Y1260000D03*
X900000Y1280000D03*
Y1220000D03*
Y1240000D03*
Y1260000D03*
X907493Y1353048D03*
X880000Y1340000D03*
X860000D03*
Y1300000D03*
Y1320000D03*
X880000D03*
Y1300000D03*
X900000Y1320000D03*
Y1300000D03*
X872875Y1346488D03*
X891250Y1348500D03*
X860000Y1420000D03*
Y1380000D03*
Y1440000D03*
X908654Y1447641D03*
X904838D03*
X868500Y1465000D03*
X859500Y1553200D03*
X873300Y1549100D03*
X859500Y1549700D03*
X901500Y1529000D03*
X855500Y1554300D03*
X860000Y1640000D03*
Y1580000D03*
X865500Y1589000D03*
X869000D03*
X873000D03*
X876500D03*
X880000Y1599000D03*
X900000Y1600000D03*
X850966Y1586525D03*
X891500Y1712000D03*
X895500D03*
Y1708000D03*
X860000Y1660000D03*
X885750Y1701500D03*
X891500Y1708000D03*
X886600Y1756100D03*
X872875Y1751600D03*
X906500Y1734100D03*
X907493Y1758560D03*
X860000Y1860000D03*
X908654Y1853153D03*
X904838D03*
X860000Y1880000D03*
X901500Y1934500D03*
X867500Y1870000D03*
X843500Y1973500D03*
X847000D03*
X852559Y1986626D03*
X872559D03*
X896546Y1986566D03*
X860000Y1980000D03*
X912559Y1986626D03*
X844800Y1949700D03*
X858800Y1951300D03*
X960000Y40000D03*
X940000D03*
X920000D03*
X950018Y5500D03*
X930018D03*
X920000Y20000D03*
X940000D03*
X960000D03*
X980000Y40000D03*
X970018Y5500D03*
X980000Y20000D03*
X960000Y120000D03*
X940000D03*
X920000D03*
Y60000D03*
X940000D03*
X960000D03*
X920000Y100000D03*
X940000D03*
X960000D03*
Y80000D03*
X940000D03*
X920000D03*
X980000Y120000D03*
Y60000D03*
Y100000D03*
Y80000D03*
X987992Y163376D03*
X960000Y140000D03*
X940000D03*
X960000Y160000D03*
X940000D03*
Y180000D03*
X960000D03*
X980000D03*
X921400Y245200D03*
X940000Y200000D03*
X960000D03*
Y220000D03*
X940000D03*
Y240000D03*
X960000D03*
Y260000D03*
X940000D03*
X980000Y240000D03*
Y260000D03*
Y200000D03*
Y220000D03*
X940000Y280000D03*
X920000D03*
X960000D03*
X920000Y300000D03*
X940000D03*
X960000D03*
X920000Y320000D03*
X940000D03*
X960000D03*
X980000Y280000D03*
Y300000D03*
Y320000D03*
X960000Y400000D03*
X940000D03*
X920000D03*
X960000Y340000D03*
X940000D03*
X920000D03*
Y360000D03*
X940000D03*
X960000D03*
Y380000D03*
X940000D03*
X920000D03*
X980000Y400000D03*
Y340000D03*
Y360000D03*
Y380000D03*
X920000Y480000D03*
X940000D03*
X960000D03*
X920000Y420000D03*
X940000D03*
X960000D03*
X920000Y440000D03*
X940000D03*
X960000D03*
X920000Y460000D03*
X940000D03*
X960000D03*
X980000Y480000D03*
Y420000D03*
Y440000D03*
Y460000D03*
X920000Y500000D03*
X940000D03*
X960000D03*
X920000Y520000D03*
X940000D03*
X960000D03*
Y540000D03*
X980000Y500000D03*
Y520000D03*
Y540000D03*
X940000Y620000D03*
X960000D03*
Y560000D03*
Y580000D03*
Y600000D03*
X940000Y580000D03*
Y600000D03*
X920000Y580000D03*
Y600000D03*
X980000Y620000D03*
Y560000D03*
Y580000D03*
Y600000D03*
X987992Y686998D03*
X920000Y700000D03*
X919000Y651511D03*
X940000Y640000D03*
X960000D03*
X920000Y680000D03*
X940000D03*
X960000D03*
Y660000D03*
X940000D03*
X920000D03*
X940000Y700000D03*
X960000D03*
X980000Y640000D03*
Y660000D03*
Y700000D03*
X940000Y760000D03*
X960000D03*
X920000D03*
Y740000D03*
Y720000D03*
X940000D03*
X960000D03*
X940000Y740000D03*
X960000D03*
X980000Y760000D03*
Y720000D03*
Y740000D03*
X940000Y840000D03*
X960000D03*
X920000D03*
X940000Y780000D03*
X960000D03*
X940000Y800000D03*
X960000D03*
X940000Y820000D03*
X960000D03*
X920000Y800000D03*
Y820000D03*
Y780000D03*
X980000Y840000D03*
Y780000D03*
Y800000D03*
Y820000D03*
X940000Y920000D03*
X960000D03*
X920000D03*
X940000Y860000D03*
X960000D03*
X940000Y880000D03*
X960000D03*
X940000Y900000D03*
X960000D03*
X920000Y860000D03*
Y880000D03*
Y900000D03*
X980000Y920000D03*
Y860000D03*
Y880000D03*
Y900000D03*
X960000Y980000D03*
Y940000D03*
X940000D03*
X960000Y960000D03*
X980000Y980000D03*
Y940000D03*
Y960000D03*
X922900Y1054200D03*
X920000Y1060000D03*
X940000D03*
X960000D03*
Y1000000D03*
X940000D03*
X920000D03*
Y1020000D03*
X940000D03*
X960000D03*
Y1040000D03*
X940000D03*
X920000D03*
X980000Y1000000D03*
Y1020000D03*
Y1040000D03*
X987992Y1082667D03*
X940000Y1140000D03*
X960000D03*
X920000Y1080000D03*
X940000D03*
X960000D03*
Y1100000D03*
X940000D03*
X920000Y1120000D03*
X940000D03*
X960000D03*
X920000Y1140000D03*
X980000D03*
Y1100000D03*
X979962Y1075211D03*
X980000Y1120000D03*
X923000Y1160200D03*
X940000Y1160000D03*
X960000D03*
Y1180000D03*
X940000D03*
X923000Y1180200D03*
X960000Y1200000D03*
X940000D03*
X920000D03*
X980000Y1160000D03*
Y1180000D03*
Y1200000D03*
X960000Y1280000D03*
X940000D03*
X920000D03*
X960000Y1220000D03*
X940000D03*
X960000Y1240000D03*
X940000D03*
X960000Y1260000D03*
X940000D03*
X920000Y1220000D03*
Y1240000D03*
Y1260000D03*
X980000Y1220000D03*
Y1240000D03*
Y1260000D03*
Y1280000D03*
X960000Y1340000D03*
X940000D03*
X920000D03*
X960000Y1300000D03*
X940000D03*
X960000Y1320000D03*
X940000D03*
X920000Y1300000D03*
Y1320000D03*
X980000Y1340000D03*
Y1300000D03*
Y1320000D03*
X981700Y1409000D03*
X954300Y1412600D03*
X960000Y1360000D03*
Y1380000D03*
Y1400000D03*
X940000D03*
X920000D03*
X963500Y1409000D03*
X973000D03*
X968000D03*
X977500D03*
X980000Y1360000D03*
Y1380000D03*
Y1400000D03*
X919000Y1462540D03*
X920000Y1480000D03*
Y1440000D03*
X965000Y1525000D03*
X955000D03*
X945000D03*
Y1516000D03*
X955000D03*
X965000D03*
X935000Y1555000D03*
X945000D03*
X955000D03*
X965000D03*
X920000Y1520000D03*
Y1540000D03*
X935000Y1575000D03*
Y1565000D03*
X945000Y1575000D03*
X955000D03*
X965000D03*
Y1565000D03*
X955000D03*
X945000D03*
X923800Y1559300D03*
X935000Y1545000D03*
Y1535000D03*
Y1525000D03*
Y1516000D03*
X965000Y1545000D03*
X955000D03*
X945000D03*
Y1535000D03*
X955000D03*
X965000D03*
X975000Y1565000D03*
Y1575000D03*
Y1525000D03*
Y1535000D03*
Y1545000D03*
Y1555000D03*
X965000Y1605000D03*
X935000Y1595000D03*
Y1585000D03*
X945000Y1595000D03*
X955000D03*
X965000D03*
Y1585000D03*
X955000D03*
X945000D03*
X923500Y1579800D03*
X920000Y1600000D03*
X975000Y1595000D03*
Y1605000D03*
Y1585000D03*
X960000Y1700000D03*
Y1720000D03*
X933000Y1704000D03*
X951500Y1658000D03*
X952000Y1678000D03*
X980000Y1700000D03*
Y1720000D03*
X963500Y1675000D03*
Y1657000D03*
X960000Y1740000D03*
Y1760000D03*
X940000D03*
X933000Y1736500D03*
X925500Y1738000D03*
X960000Y1780000D03*
X980000D03*
Y1740000D03*
Y1760000D03*
X960000Y1860000D03*
X940000D03*
X960000Y1800000D03*
X940000D03*
X920000D03*
X940000Y1820000D03*
X960000D03*
X940000Y1840000D03*
X960000D03*
X920000D03*
X980000Y1860000D03*
Y1800000D03*
Y1820000D03*
Y1840000D03*
X987992Y1903534D03*
X920000Y1920000D03*
X940000D03*
X960000D03*
Y1940000D03*
X940000D03*
X920000D03*
X919000Y1868047D03*
X960000Y1880000D03*
X940000D03*
X920000D03*
X960000Y1900000D03*
X940000D03*
X920000D03*
X980000Y1920000D03*
Y1940000D03*
X980018Y1897856D03*
X932559Y1986626D03*
X952559D03*
X960000Y1960000D03*
X940000D03*
X920000D03*
Y1980000D03*
X940000D03*
X960000D03*
X972559Y1986626D03*
X980000Y1960000D03*
Y1980000D03*
X1031902Y43616D03*
X1020000Y40000D03*
X1000000D03*
X1031902Y23616D03*
X1030018Y5500D03*
X1010018D03*
X990018D03*
X1000000Y20000D03*
X1020000D03*
Y120000D03*
X1000000D03*
X1031902Y63616D03*
Y103616D03*
Y83616D03*
X1000000Y60000D03*
X1020000D03*
X1000000Y100000D03*
X1020000D03*
Y80000D03*
X1000000D03*
X989330Y168376D03*
X992992Y172077D03*
X1003031D03*
X1006732Y168376D03*
X1008070Y163376D03*
X1031902Y143616D03*
Y123616D03*
Y163616D03*
X1020000Y140000D03*
Y160000D03*
Y180000D03*
X1031902Y183616D03*
X1000000Y240000D03*
X1020000D03*
X1031902Y263616D03*
X1020000Y260000D03*
X1000000D03*
X1031902Y223616D03*
Y203616D03*
Y243616D03*
X1000000Y200000D03*
X1020000D03*
Y220000D03*
X1000000D03*
X1031902Y303616D03*
Y283616D03*
Y323616D03*
X1000000Y280000D03*
X1020000D03*
X1000000Y300000D03*
X1020000D03*
X1000000Y320000D03*
X1020000D03*
X1031902Y403616D03*
X1020000Y400000D03*
X1000000D03*
X1031902Y383616D03*
Y363616D03*
Y343616D03*
X1020000Y340000D03*
X1000000D03*
Y360000D03*
X1020000D03*
Y380000D03*
X1000000D03*
X1031902Y483616D03*
X1000000Y480000D03*
X1020000D03*
X1031902Y443616D03*
Y423616D03*
Y463616D03*
X1000000Y420000D03*
X1020000D03*
X1000000Y440000D03*
X1020000D03*
X1000000Y460000D03*
X1020000D03*
X1031902Y523616D03*
Y503616D03*
Y543616D03*
X1000000Y500000D03*
X1020000D03*
X1000000Y520000D03*
X1020000D03*
X1000000Y540000D03*
X1020000D03*
X1031902Y623616D03*
X1000000Y620000D03*
X1020000D03*
X1031902Y603616D03*
Y583616D03*
Y563616D03*
X1020000Y560000D03*
X1000000D03*
X1020000Y580000D03*
X1000000D03*
X1020000Y600000D03*
X1000000D03*
X989330Y691998D03*
X992992Y695699D03*
X1003031D03*
X1006732Y691998D03*
X1008070Y686998D03*
X1031902Y683616D03*
Y663616D03*
Y643616D03*
X1000000Y640000D03*
X1020000D03*
Y660000D03*
Y680000D03*
Y700000D03*
X1000000Y740000D03*
X1020000D03*
X1000000Y760000D03*
X1020000D03*
X1031902Y763616D03*
Y743616D03*
Y723616D03*
Y703616D03*
X1000000Y720000D03*
X1020000D03*
X1031902Y843616D03*
X1000000Y840000D03*
X1020000D03*
X1031902Y823616D03*
Y803616D03*
Y783616D03*
X1000000Y780000D03*
X1020000D03*
X1000000Y800000D03*
X1020000D03*
X1000000Y820000D03*
X1020000D03*
X1000000Y920000D03*
X1020000D03*
X1031902Y903616D03*
Y883616D03*
Y863616D03*
X1000000Y860000D03*
X1020000D03*
X1000000Y880000D03*
X1020000D03*
X1000000Y900000D03*
X1020000D03*
X1031902Y983616D03*
X1000000Y980000D03*
X1020000D03*
X1031902Y963616D03*
Y943616D03*
Y923616D03*
X1020000Y940000D03*
X1000000D03*
Y960000D03*
X1020000D03*
X1031902Y1063616D03*
X1020000Y1060000D03*
X1031902Y1043616D03*
Y1023616D03*
Y1003616D03*
X1020000Y1000000D03*
X1000000D03*
Y1020000D03*
X1020000D03*
Y1040000D03*
X1000000D03*
X989330Y1087667D03*
X992992Y1091368D03*
X1003031D03*
X1006732Y1087667D03*
X1008070Y1082667D03*
X1031902Y1123616D03*
X1000000Y1140000D03*
X1020000D03*
X1031902Y1103616D03*
Y1083616D03*
X1020000Y1080000D03*
Y1100000D03*
X999922Y1102598D03*
X1000000Y1120000D03*
X1020000D03*
X1031902Y1143616D03*
Y1183616D03*
Y1163616D03*
X1000000Y1160000D03*
X1020000D03*
Y1180000D03*
X1000000D03*
X1031902Y1203616D03*
X1020000Y1200000D03*
X1000000D03*
Y1220000D03*
X1020000Y1240000D03*
X1000000D03*
X1020000Y1260000D03*
X1000000D03*
X1031902Y1283616D03*
X1020000Y1280000D03*
X1000000D03*
X1031902Y1263616D03*
Y1243616D03*
Y1223616D03*
X1020000Y1220000D03*
X1031902Y1343616D03*
X1020000Y1340000D03*
X1000000D03*
X1031902Y1323616D03*
Y1303616D03*
X1020000Y1300000D03*
X1000000D03*
X1020000Y1320000D03*
X1000000D03*
X986200Y1409000D03*
X994600Y1414100D03*
X990300Y1412500D03*
X1031902Y1363616D03*
Y1383616D03*
X1020000Y1360000D03*
X1000000D03*
Y1380000D03*
X1020000D03*
Y1400000D03*
X1000000D03*
X994898Y1646102D03*
X992500Y1636000D03*
X991602Y1622500D03*
X1000000Y1700000D03*
X1020000Y1720000D03*
X1000000D03*
X995102Y1676102D03*
X995000Y1656102D03*
Y1666102D03*
X1031902Y1785969D03*
X1000000Y1780000D03*
X1020000D03*
X1031902Y1745969D03*
Y1725969D03*
Y1765969D03*
X1000000Y1740000D03*
X1020000D03*
Y1760000D03*
X1000000D03*
X1031902Y1865969D03*
Y1845969D03*
X1020000Y1860000D03*
X1000000D03*
X1031902Y1805969D03*
Y1825969D03*
X1020000Y1800000D03*
X1000000D03*
Y1820000D03*
X1020000D03*
X1000000Y1840000D03*
X1020000D03*
X989330Y1908534D03*
X992992Y1912235D03*
X1003031D03*
X1006732Y1908534D03*
X1008070Y1903534D03*
X1031902Y1925969D03*
X999469Y1923465D03*
X1020000Y1920000D03*
Y1940000D03*
X1000000D03*
X1031902Y1885969D03*
Y1905969D03*
X1020000Y1880000D03*
Y1900000D03*
X1031902Y1965969D03*
Y1945969D03*
X992559Y1986626D03*
X1012559D03*
X1031902Y1985969D03*
X1020000Y1960000D03*
X1000000D03*
Y1980000D03*
X1020000D03*
G54D20*
X31981Y1768323D03*
X135064Y213390D03*
X134941Y264178D03*
X135095Y288972D03*
X134995Y301768D03*
X135095Y625402D03*
X158500Y569500D03*
X134941Y669690D03*
X135095Y694484D03*
X134993Y707280D03*
X135095Y1030914D03*
X134941Y1075202D03*
X135095Y1099996D03*
X135001Y1112792D03*
X135095Y1436426D03*
X134935Y1480714D03*
X135095Y1505508D03*
X134995Y1518304D03*
X153700Y1633600D03*
X135065Y1835438D03*
X134895Y1905020D03*
X863441Y219890D03*
X863307Y269678D03*
X863441Y288972D03*
X863346Y301768D03*
X863441Y625402D03*
Y694484D03*
X863287Y669690D03*
X863397Y713280D03*
X863441Y1030914D03*
X863346Y1112792D03*
X863441Y1099996D03*
X863308Y1080702D03*
X863286Y1480714D03*
X863441Y1436426D03*
X863347Y1518304D03*
X863441Y1505508D03*
Y1841938D03*
X863346Y1923816D03*
X863441Y1911020D03*
X863287Y1886226D03*
G54D23*
X82087Y28858D03*
Y178464D03*
Y434370D03*
Y583976D03*
Y839882D03*
Y989488D03*
Y1245394D03*
Y1395000D03*
Y1650906D03*
Y1800512D03*
X162008Y191614D03*
Y341220D03*
Y597126D03*
Y746732D03*
Y1002638D03*
Y1152244D03*
Y1408150D03*
Y1557756D03*
Y1813662D03*
Y1963268D03*
X890354Y191614D03*
Y341220D03*
Y597126D03*
Y746732D03*
Y1002638D03*
Y1152244D03*
Y1408150D03*
Y1557756D03*
Y1813662D03*
Y1963268D03*
G54D10*
X-63741Y15000D03*
X-42339Y1008909D03*
X-63741Y1977126D03*
X25499Y1950499D03*
X1010999Y43999D03*
X1010499Y1950499D03*
X1101142Y15000D03*
Y1977126D03*
G54D14*
X11811Y571426D03*
Y949378D03*
Y1067489D03*
Y1484811D03*
Y1445441D03*
Y1862763D03*
G54D18*
X33469Y1029523D03*
X269690Y1490152D03*
G54D28*
X1023228Y1416024D03*
Y1694212D03*
G36*
G01X43453Y275788D02*
G02X23476I-9988J-8073D01*
G03X24559Y278851I-3790J3063D01*
G01Y281496D01*
G02X42370I8906J0D01*
G01Y278851D01*
G03X43453Y275788I4873J0D01*
G37*
G36*
G01X31642Y1917127D02*
G02X11665I-9989J-8073D01*
G03X12748Y1920190I-3790J3063D01*
G01Y1922835D01*
G02X30559I8906J0D01*
G01Y1920190D01*
G03X31642Y1917127I4873J0D01*
G37*
G36*
G01X143846Y12009D02*
G02X123869I-9988J-8073D01*
G03X124952Y15072I-3790J3063D01*
G01Y17717D01*
G02X142763I8905J0D01*
G01Y15072D01*
G03X143846Y12009I4873J0D01*
G37*
G36*
G01X285579Y273820D02*
G02X265602I-9988J-8073D01*
G03X266685Y276883I-3790J3063D01*
G01Y279528D01*
G02X284496I8906J0D01*
G01Y276883D01*
G03X285579Y273820I4873J0D01*
G37*
G36*
G01Y679322D02*
G02X265602I-9988J-8073D01*
G03X266685Y682385I-3790J3063D01*
G01Y685030D01*
G02X284496I8906J0D01*
G01Y682385D01*
G03X285579Y679322I4873J0D01*
G37*
G36*
G01Y1082865D02*
G02X265602I-9988J-8073D01*
G03X266685Y1085928I-3790J3063D01*
G01Y1088573D01*
G02X284496I8906J0D01*
G01Y1085928D01*
G03X285579Y1082865I4873J0D01*
G37*
G36*
G01Y1897826D02*
G02X265602I-9988J-8073D01*
G03X266685Y1900889I-3790J3063D01*
G01Y1903534D01*
G02X284496I8906J0D01*
G01Y1900889D01*
G03X285579Y1897826I4873J0D01*
G37*
G36*
G01X1008019Y157668D02*
G02X988042I-9989J-8073D01*
G03X989125Y160731I-3790J3063D01*
G01Y163376D01*
G02X1006936I8906J0D01*
G01Y160731D01*
G03X1008019Y157668I4873J0D01*
G37*
G36*
G01Y681290D02*
G02X988042I-9989J-8073D01*
G03X989125Y684353I-3790J3063D01*
G01Y686998D01*
G02X1006936I8906J0D01*
G01Y684353D01*
G03X1008019Y681290I4873J0D01*
G37*
G36*
G01Y1076959D02*
G02X988042I-9989J-8073D01*
G03X989125Y1080022I-3790J3063D01*
G01Y1082667D01*
G02X1006936I8906J0D01*
G01Y1080022D01*
G03X1008019Y1076959I4873J0D01*
G37*
G36*
G01Y1897826D02*
G02X988042I-9989J-8073D01*
G03X989125Y1900889I-3790J3063D01*
G01Y1903534D01*
G02X1006936I8906J0D01*
G01Y1900889D01*
G03X1008019Y1897826I4873J0D01*
G37*
G54D13*
X27500Y380000D03*
X27000Y440000D03*
X27500Y540000D03*
Y553500D03*
X34000Y1321000D03*
X21000Y1424500D03*
X22000Y1487000D03*
X37000Y1443500D03*
X30500Y1463500D03*
X71000Y58000D03*
X97000Y296500D03*
X111500Y276000D03*
X84500Y315000D03*
X67000Y269000D03*
X66512Y287899D03*
X46487Y360400D03*
X48822Y393916D03*
X100400Y406000D03*
X104400D03*
X107900D03*
X96900D03*
X51500Y469000D03*
X112600Y442500D03*
X98300Y443400D03*
X71000Y463500D03*
X112600Y439000D03*
X99900Y582400D03*
X61900Y584300D03*
X72900Y605400D03*
X94700Y599800D03*
X59000Y659500D03*
X49000Y638000D03*
X76500Y665000D03*
X62000Y736500D03*
X61500Y748000D03*
X51500Y730500D03*
Y757500D03*
X63100Y788800D03*
X73500Y779500D03*
X100600Y811300D03*
X104600D03*
X108100D03*
X97100D03*
X112500Y848700D03*
Y845200D03*
X98300Y850400D03*
X71000Y869000D03*
X75000Y1182500D03*
X41500Y1165500D03*
Y1178000D03*
X67500Y1191500D03*
X81500Y1213000D03*
X99100Y1219800D03*
X104500Y1217000D03*
X108000D03*
X95700Y1219700D03*
X112600Y1254300D03*
X98300Y1255900D03*
X71000Y1274500D03*
X112600Y1250800D03*
X64000Y1328500D03*
X58500Y1320500D03*
X48000Y1482000D03*
Y1505500D03*
X91125Y1565900D03*
X100500Y1622500D03*
X104500D03*
X108000D03*
X97000D03*
X98600Y1659800D03*
X71000Y1680000D03*
X170034Y31475D03*
X135500Y200500D03*
X125500Y265500D03*
X132500Y236000D03*
X128500Y248000D03*
X135064Y219602D03*
X171595Y203917D03*
X148095Y211771D03*
X171595Y218917D03*
X148095Y221220D03*
X171595Y233917D03*
X148095Y230669D03*
Y236968D03*
Y246417D03*
Y255866D03*
Y262165D03*
X126000Y293000D03*
X125000Y312000D03*
X134941Y269602D03*
X135095Y282602D03*
X134995Y307602D03*
X148095Y271614D03*
Y281063D03*
Y290511D03*
Y299960D03*
Y309409D03*
Y318858D03*
X171595Y278917D03*
Y283917D03*
X119159Y405100D03*
X163500Y423000D03*
X135095Y618614D03*
X171595Y609429D03*
X148095Y617283D03*
X171595Y624429D03*
X148095Y626732D03*
X134941Y675114D03*
X135095Y688114D03*
X171895Y639429D03*
X148095Y636181D03*
Y642480D03*
Y651929D03*
Y661378D03*
Y667677D03*
Y677126D03*
Y686575D03*
Y696023D03*
X171595Y684429D03*
Y689429D03*
X134993Y713114D03*
X148095Y705472D03*
Y714921D03*
Y724370D03*
X119534Y810975D03*
X135095Y1024126D03*
X171595Y1014941D03*
X148095Y1022795D03*
X171595Y1029941D03*
X148095Y1032244D03*
X171595Y1044941D03*
X148095Y1041693D03*
Y1047992D03*
Y1057441D03*
Y1066890D03*
X134941Y1080626D03*
X135095Y1093626D03*
X135001Y1118626D03*
X148095Y1073189D03*
Y1082638D03*
Y1092087D03*
Y1101535D03*
Y1110984D03*
Y1120433D03*
Y1129882D03*
X171595Y1089941D03*
Y1094941D03*
X119534Y1216475D03*
X135095Y1429638D03*
X171595Y1420453D03*
X148095Y1428307D03*
X134935Y1486138D03*
X135095Y1499138D03*
X171595Y1435453D03*
X148095Y1437756D03*
X171895Y1450453D03*
X148095Y1447205D03*
Y1453504D03*
Y1462953D03*
Y1472402D03*
Y1478701D03*
Y1488150D03*
Y1497599D03*
X171595Y1495453D03*
Y1500453D03*
X134995Y1524138D03*
X148095Y1507047D03*
Y1516496D03*
Y1525945D03*
Y1535394D03*
X119534Y1621975D03*
X113200Y1659800D03*
Y1656300D03*
X135065Y1841650D03*
X171595Y1825965D03*
X148095Y1833819D03*
X171595Y1840965D03*
X148095Y1843268D03*
X171595Y1855965D03*
X148095Y1852717D03*
Y1859016D03*
X134895Y1886150D03*
Y1891650D03*
Y1910650D03*
X134995Y1923650D03*
Y1929650D03*
X148095Y1868465D03*
Y1877914D03*
Y1884213D03*
Y1893662D03*
Y1903111D03*
Y1912559D03*
Y1922008D03*
Y1931457D03*
X171595Y1900965D03*
Y1905965D03*
X148095Y1940906D03*
X190500Y639713D03*
X370128Y361337D03*
X349706Y355693D03*
X356250Y349000D03*
X368500Y364500D03*
X372000D03*
X383750Y349000D03*
X391800Y355800D03*
X362000Y797000D03*
X365500D03*
X358000Y794000D03*
X377250Y779000D03*
X385250Y785700D03*
X371000Y1168000D03*
X367500D03*
X363500Y1165000D03*
X383750Y1150500D03*
X391765Y1157852D03*
X348250Y1649000D03*
X368500Y1664000D03*
X372500Y1667000D03*
X376000D03*
X356238Y1655722D03*
X876441Y262165D03*
Y255866D03*
X863307Y264102D03*
X876441Y246417D03*
Y236968D03*
Y230669D03*
Y221220D03*
Y211771D03*
X863441Y213102D03*
X899941Y233917D03*
Y218917D03*
Y203917D03*
X876441Y318858D03*
Y309409D03*
Y299960D03*
Y290511D03*
Y281063D03*
Y271614D03*
X863346Y307602D03*
X863441Y282602D03*
X899941Y283917D03*
Y278917D03*
X876441Y626732D03*
Y617283D03*
X863441Y618614D03*
X899941Y624429D03*
Y609429D03*
X876441Y661378D03*
Y651929D03*
Y642480D03*
Y636181D03*
X863287Y675114D03*
X863441Y688114D03*
X876441Y696023D03*
Y686575D03*
Y677126D03*
Y667677D03*
X899941Y684429D03*
Y639429D03*
Y689429D03*
X876441Y724370D03*
Y714921D03*
Y705472D03*
X863397Y707114D03*
X876441Y1066890D03*
Y1057441D03*
Y1047992D03*
Y1041693D03*
Y1032244D03*
Y1022795D03*
X863441Y1024126D03*
X899941Y1044941D03*
Y1029941D03*
Y1014941D03*
X876441Y1129882D03*
Y1120433D03*
Y1110984D03*
Y1101535D03*
Y1092087D03*
Y1082638D03*
Y1073189D03*
X863308Y1075126D03*
X863441Y1093626D03*
X863346Y1118626D03*
X899941Y1094941D03*
Y1089941D03*
X876441Y1428307D03*
X863441Y1429638D03*
X899941Y1420453D03*
X876441Y1478701D03*
Y1472402D03*
Y1462953D03*
Y1453504D03*
Y1447205D03*
Y1437756D03*
Y1497599D03*
Y1488150D03*
X863286Y1486138D03*
X863441Y1499138D03*
X899941Y1450453D03*
Y1435453D03*
Y1500453D03*
Y1495453D03*
X876441Y1535394D03*
Y1525945D03*
Y1516496D03*
Y1507047D03*
X863347Y1524138D03*
X876441Y1859016D03*
Y1852717D03*
Y1843268D03*
Y1833819D03*
X863441Y1835150D03*
X899941Y1855965D03*
Y1840965D03*
Y1825965D03*
X876441Y1912559D03*
Y1903111D03*
Y1893662D03*
Y1884213D03*
Y1877914D03*
Y1868465D03*
X863287Y1891650D03*
X863441Y1904650D03*
X876441Y1931457D03*
Y1922008D03*
X863346Y1929650D03*
X899941Y1905965D03*
Y1900965D03*
X876441Y1940906D03*
G54D24*
X97400Y366600D03*
X97000Y772100D03*
X96100Y1176700D03*
X88076Y1575924D03*
X43935Y1957215D03*
X824335Y365915D03*
Y771415D03*
Y1176915D03*
Y1582415D03*
X774989Y1955708D03*
G54D25*
X95849Y361564D03*
X87900Y1173300D03*
X56875Y1954250D03*
X182000Y949000D03*
X292200Y1688900D03*
X295800D03*
X374300Y81400D03*
X378100Y81500D03*
X414281Y820751D03*
X421000Y812750D03*
X420743Y1215266D03*
X414274Y1223246D03*
X421000Y1713750D03*
X414299Y1721750D03*
X815375Y362750D03*
Y768250D03*
Y1173750D03*
X816625Y1579250D03*
X780214Y1953257D03*
G54D27*
X145900Y408500D03*
X147100Y814200D03*
X146700Y1219600D03*
X143500Y1625500D03*
X196665Y35585D03*
G54D15*
X24500Y619093D03*
Y606544D03*
Y694733D03*
Y682135D03*
Y669537D03*
Y644340D03*
Y631741D03*
Y763825D03*
Y732329D03*
Y719730D03*
Y707332D03*
Y848664D03*
Y836266D03*
Y823667D03*
Y811069D03*
Y798470D03*
Y776423D03*
Y911856D03*
Y899258D03*
Y886509D03*
Y873861D03*
Y861263D03*
Y1133365D03*
Y1095769D03*
Y1108368D03*
Y1208955D03*
Y1196357D03*
Y1183758D03*
Y1171160D03*
Y1158562D03*
Y1145963D03*
Y1278247D03*
Y1265648D03*
Y1253050D03*
Y1221554D03*
Y1350888D03*
Y1338289D03*
Y1325691D03*
Y1313092D03*
Y1290845D03*
Y1401081D03*
Y1388483D03*
Y1375884D03*
Y1363286D03*
Y1566907D03*
Y1554308D03*
Y1529111D03*
Y1541710D03*
Y1639348D03*
Y1626749D03*
Y1614151D03*
Y1601552D03*
Y1588954D03*
Y1702531D03*
Y1689932D03*
Y1677334D03*
Y1762373D03*
Y1749775D03*
Y1737176D03*
Y1724578D03*
X109038Y62310D03*
X109000Y81106D03*
X109160Y105900D03*
X67500Y124088D03*
X108917Y150188D03*
X109044Y467822D03*
X109000Y486618D03*
X109138Y505912D03*
X67500Y529600D03*
X108917Y555700D03*
X109040Y873334D03*
X109000Y892130D03*
X109187Y911424D03*
X67500Y935111D03*
X109000Y961212D03*
X109040Y1278846D03*
X109000Y1297642D03*
X109133Y1316936D03*
X67500Y1340624D03*
X109000Y1366724D03*
X109040Y1684358D03*
X109000Y1703154D03*
X109137Y1722448D03*
X67500Y1757886D03*
X109030Y1778736D03*
X194500Y236902D03*
X190600Y1045226D03*
X190400Y1462536D03*
X194620Y1859298D03*
X921400Y235002D03*
X919000Y639715D03*
X922900Y1048050D03*
X919000Y1450734D03*
Y1856251D03*
G54D26*
X87075Y768250D03*
%LPC*%
G75*
G54D30*
G01X-90900Y-277455D02*
Y-294955D01*
X-82166D01*
G01X-69033Y-283289D02*
Y-294955D01*
G01Y-278622D02*
X-69470Y-278330D01*
Y-277747D01*
X-69033Y-277455D01*
X-68596Y-277747D01*
Y-278330D01*
X-69033Y-278622D01*
G01X-54590Y-299330D02*
X-53061Y-300497D01*
X-51315Y-300788D01*
X-49787Y-300497D01*
X-48476Y-299039D01*
X-47603Y-296997D01*
Y-283289D01*
G01Y-285622D02*
X-48476Y-284455D01*
X-49787Y-283580D01*
X-51315Y-283289D01*
X-53061Y-283872D01*
X-54153Y-285038D01*
X-55027Y-287080D01*
X-55463Y-289122D01*
X-55245Y-290872D01*
X-54371Y-292914D01*
X-53061Y-294372D01*
X-51315Y-294955D01*
X-50005Y-294663D01*
X-48476Y-293497D01*
X-47603Y-292331D01*
G01X-37745Y-294955D02*
Y-277455D01*
G01Y-285913D02*
X-36653Y-284455D01*
X-35561Y-283580D01*
X-33815Y-283289D01*
X-32505Y-283580D01*
X-30976Y-284747D01*
X-30321Y-286497D01*
Y-294955D01*
G01X-16533Y-277455D02*
Y-294955D01*
G01X-19590Y-283289D02*
X-13476D01*
G01X-2745Y-294955D02*
Y-283289D01*
G01Y-286205D02*
X-1871Y-284747D01*
X-561Y-283580D01*
X1185Y-283289D01*
X2713Y-283580D01*
X4024Y-284747D01*
X4679Y-286788D01*
Y-294955D01*
G01X18467Y-283289D02*
Y-294955D01*
G01Y-278622D02*
X18030Y-278330D01*
Y-277747D01*
X18467Y-277455D01*
X18904Y-277747D01*
Y-278330D01*
X18467Y-278622D01*
G01X32255Y-294955D02*
Y-283289D01*
G01Y-286205D02*
X33129Y-284747D01*
X34439Y-283580D01*
X36185Y-283289D01*
X37713Y-283580D01*
X39024Y-284747D01*
X39679Y-286788D01*
Y-294955D01*
G01X50410Y-299330D02*
X51939Y-300497D01*
X53685Y-300788D01*
X55213Y-300497D01*
X56524Y-299039D01*
X57397Y-296997D01*
Y-283289D01*
G01Y-285622D02*
X56524Y-284455D01*
X55213Y-283580D01*
X53685Y-283289D01*
X51939Y-283872D01*
X50847Y-285038D01*
X49973Y-287080D01*
X49537Y-289122D01*
X49755Y-290872D01*
X50629Y-292914D01*
X51939Y-294372D01*
X53685Y-294955D01*
X54995Y-294663D01*
X56524Y-293497D01*
X57397Y-292331D01*
G01X84100Y-294955D02*
Y-277455D01*
X89340D01*
X91087Y-278330D01*
X92397Y-280372D01*
X92834Y-282705D01*
X92397Y-285038D01*
X91305Y-286788D01*
X89340Y-287664D01*
X84100D01*
G01X101164Y-294955D02*
Y-277455D01*
X105530D01*
X107277Y-278330D01*
X108587Y-279497D01*
X109679Y-281246D01*
X110552Y-283289D01*
X110770Y-286205D01*
X110552Y-289122D01*
X109679Y-291164D01*
X108587Y-292914D01*
X107277Y-294080D01*
X105530Y-294955D01*
X101164D01*
G01X119100D02*
Y-277455D01*
X124340D01*
X126087Y-278330D01*
X127397Y-280372D01*
X127834Y-282705D01*
X127397Y-285038D01*
X126305Y-286788D01*
X124340Y-287664D01*
X119100D01*
G01X142713Y-285622D02*
X143587Y-284747D01*
X144242Y-283289D01*
X144679Y-281246D01*
X144242Y-279497D01*
X143369Y-278330D01*
X141840Y-277455D01*
X135945D01*
Y-294955D01*
X143150D01*
X144679Y-293789D01*
X145552Y-292038D01*
X145989Y-289997D01*
X145552Y-287955D01*
X144242Y-286205D01*
X142713Y-285622D01*
X135945D01*
G01X171600Y-294955D02*
Y-277455D01*
X176840D01*
X178587Y-278330D01*
X179897Y-280372D01*
X180334Y-282705D01*
X179897Y-285038D01*
X178805Y-286788D01*
X176840Y-287664D01*
X171600D01*
G01X188008Y-277455D02*
X193467Y-294955D01*
X198926Y-277455D01*
G01X210967D02*
Y-294955D01*
G01X205945Y-277455D02*
X215989D01*
G01X21540Y-249955D02*
Y-232455D01*
X27217Y-247038D01*
X32894Y-232455D01*
Y-249955D01*
G01X44717D02*
X43407Y-249663D01*
X42097Y-248497D01*
X41223Y-246455D01*
X40787Y-244122D01*
X41223Y-241788D01*
X42097Y-239747D01*
X43407Y-238580D01*
X44717Y-238289D01*
X46027Y-238580D01*
X47337Y-239747D01*
X48210Y-241788D01*
X48429Y-244122D01*
X48210Y-246455D01*
X47337Y-248497D01*
X46027Y-249663D01*
X44717Y-249955D01*
G01X66147Y-232455D02*
Y-249955D01*
G01Y-247331D02*
X65274Y-248789D01*
X63963Y-249663D01*
X62435Y-249955D01*
X60689Y-249372D01*
X59379Y-247914D01*
X58505Y-246164D01*
X58287Y-244122D01*
X58505Y-242080D01*
X59379Y-240330D01*
X60689Y-238872D01*
X62435Y-238289D01*
X63963Y-238580D01*
X65055Y-239164D01*
X66147Y-240330D01*
G01X76442Y-242080D02*
X83429D01*
X82774Y-240038D01*
X81682Y-238872D01*
X80154Y-238289D01*
X78625Y-238580D01*
X77315Y-239455D01*
X76442Y-241497D01*
X76005Y-243247D01*
Y-244997D01*
X76442Y-246747D01*
X77534Y-248497D01*
X78844Y-249663D01*
X80372Y-249955D01*
X81900Y-249372D01*
X83429Y-247622D01*
G01X97217Y-249955D02*
Y-232455D01*
G01X252500Y-249955D02*
Y-232455D01*
X257740D01*
X259487Y-233330D01*
X260797Y-235372D01*
X261234Y-237705D01*
X260797Y-240038D01*
X259705Y-241788D01*
X257740Y-242664D01*
X252500D01*
G01X279170Y-233914D02*
X277860Y-233038D01*
X276332Y-232455D01*
X274585D01*
X272620Y-233330D01*
X271092Y-234788D01*
X270000Y-236539D01*
X269127Y-239455D01*
X268908Y-242080D01*
X269345Y-244705D01*
X270000Y-246455D01*
X271310Y-248205D01*
X272839Y-249372D01*
X274367Y-249955D01*
X275895D01*
X277424Y-249372D01*
X278734Y-248497D01*
X279826Y-247331D01*
G01X293613Y-240622D02*
X294487Y-239747D01*
X295142Y-238289D01*
X295579Y-236246D01*
X295142Y-234497D01*
X294269Y-233330D01*
X292740Y-232455D01*
X286845D01*
Y-249955D01*
X294050D01*
X295579Y-248789D01*
X296452Y-247038D01*
X296889Y-244997D01*
X296452Y-242955D01*
X295142Y-241205D01*
X293613Y-240622D01*
X286845D01*
G01X302817Y-255788D02*
X315917D01*
G01X321845Y-249955D02*
Y-232455D01*
X331889Y-249955D01*
Y-232455D01*
G01X344367Y-249955D02*
X342620Y-249663D01*
X341092Y-248497D01*
X339782Y-246747D01*
X338908Y-244705D01*
X338472Y-242372D01*
Y-240038D01*
X338908Y-237705D01*
X339782Y-235663D01*
X341092Y-233914D01*
X342620Y-232747D01*
X344367Y-232455D01*
X346113Y-232747D01*
X347642Y-233914D01*
X348952Y-235663D01*
X349826Y-237705D01*
X350262Y-240038D01*
Y-242372D01*
X349826Y-244705D01*
X348952Y-246747D01*
X347642Y-248497D01*
X346113Y-249663D01*
X344367Y-249955D01*
G01X265617Y-294955D02*
Y-277455D01*
X262997Y-280955D01*
G01Y-294955D02*
X268237D01*
G01X278314Y-292331D02*
X279623Y-293789D01*
X281152Y-294663D01*
X283117Y-294955D01*
X285082Y-294372D01*
X286610Y-293205D01*
X287702Y-291164D01*
X287920Y-288830D01*
X287484Y-286497D01*
X286392Y-285038D01*
X284863Y-283872D01*
X283335Y-283580D01*
X281807Y-283872D01*
X279842Y-285038D01*
X280497Y-277455D01*
X286392D01*
G01X296469Y-287664D02*
X297997Y-285622D01*
X299307Y-284455D01*
X301054Y-283872D01*
X302582Y-284455D01*
X303674Y-285622D01*
X304547Y-287372D01*
X304765Y-289413D01*
X304547Y-291164D01*
X303674Y-292914D01*
X302363Y-294372D01*
X300835Y-294955D01*
X299089Y-294372D01*
X297560Y-292622D01*
X296687Y-289997D01*
X296469Y-287080D01*
X296905Y-283289D01*
X297560Y-281246D01*
X298652Y-279205D01*
X300180Y-277747D01*
X301709Y-277455D01*
X303237Y-278038D01*
X304329Y-279497D01*
G01X313969Y-287664D02*
X315497Y-285622D01*
X316807Y-284455D01*
X318554Y-283872D01*
X320082Y-284455D01*
X321174Y-285622D01*
X322047Y-287372D01*
X322265Y-289413D01*
X322047Y-291164D01*
X321174Y-292914D01*
X319863Y-294372D01*
X318335Y-294955D01*
X316589Y-294372D01*
X315060Y-292622D01*
X314187Y-289997D01*
X313969Y-287080D01*
X314405Y-283289D01*
X315060Y-281246D01*
X316152Y-279205D01*
X317680Y-277747D01*
X319209Y-277455D01*
X320737Y-278038D01*
X321829Y-279497D01*
G01X331905Y-292914D02*
X333434Y-294372D01*
X335180Y-294955D01*
X336927Y-294372D01*
X338455Y-292622D01*
X339547Y-289997D01*
X339984Y-287372D01*
Y-284164D01*
X339547Y-281539D01*
X338455Y-279205D01*
X337145Y-278038D01*
X335617Y-277455D01*
X333870Y-278038D01*
X332560Y-279205D01*
X331687Y-280955D01*
X331250Y-283289D01*
X331687Y-285330D01*
X332779Y-287372D01*
X334089Y-288539D01*
X335617Y-288830D01*
X337363Y-288247D01*
X338674Y-286788D01*
X339984Y-284164D01*
G01X395208Y-232455D02*
X400667Y-249955D01*
X406126Y-232455D01*
G01X422534Y-249955D02*
X413800D01*
Y-232455D01*
X422534D01*
G01X419040Y-240913D02*
X413800D01*
G01X431300Y-249955D02*
Y-232455D01*
X436759D01*
X438505Y-233330D01*
X439597Y-234497D01*
X440034Y-236830D01*
X439597Y-239164D01*
X438287Y-240622D01*
X436759Y-241497D01*
X431300D01*
G01X436759D02*
X440034Y-249955D01*
G01X453167Y-250538D02*
X452730Y-250247D01*
Y-249663D01*
X453167Y-249372D01*
X453604Y-249663D01*
Y-250247D01*
X453167Y-250538D01*
G01X426917Y-294955D02*
Y-277455D01*
X424297Y-280955D01*
G01Y-294955D02*
X429537D01*
G01X528750Y-232455D02*
Y-249955D01*
X537484D01*
G01X554547D02*
Y-238289D01*
G01Y-240330D02*
X553674Y-239164D01*
X552363Y-238580D01*
X550835Y-238289D01*
X549307Y-238872D01*
X547997Y-240038D01*
X547123Y-241788D01*
X546687Y-244122D01*
X547123Y-246455D01*
X547997Y-248205D01*
X549307Y-249372D01*
X550835Y-249955D01*
X552363Y-249663D01*
X553674Y-248789D01*
X554547Y-247622D01*
G01X563532Y-255205D02*
X564842Y-255788D01*
X566589Y-255205D01*
X567680Y-254039D01*
X568554Y-252580D01*
X569863Y-247914D01*
X572702Y-238289D01*
G01X565715D02*
X569863Y-247914D01*
G01X582342Y-242080D02*
X589329D01*
X588674Y-240038D01*
X587582Y-238872D01*
X586054Y-238289D01*
X584525Y-238580D01*
X583215Y-239455D01*
X582342Y-241497D01*
X581905Y-243247D01*
Y-244997D01*
X582342Y-246747D01*
X583434Y-248497D01*
X584744Y-249663D01*
X586272Y-249955D01*
X587800Y-249372D01*
X589329Y-247622D01*
G01X600060Y-249955D02*
Y-238289D01*
G01Y-240622D02*
X601152Y-239455D01*
X602244Y-238580D01*
X603772Y-238289D01*
X604863Y-238580D01*
X606174Y-239455D01*
G01X528750Y-277455D02*
Y-294955D01*
X537484D01*
G01X546469Y-280372D02*
X547779Y-278622D01*
X549307Y-277747D01*
X551054Y-277455D01*
X553237Y-278038D01*
X554765Y-279497D01*
X555202Y-281246D01*
X554984Y-282997D01*
X554110Y-284455D01*
X549744Y-287372D01*
X547779Y-289413D01*
X546469Y-292331D01*
X546032Y-294955D01*
X555202D01*
G01X569427Y-286205D02*
X573794D01*
Y-291455D01*
X572484Y-293205D01*
X570955Y-294372D01*
X568772Y-294955D01*
X566589Y-294372D01*
X565060Y-293205D01*
X563750Y-291455D01*
X562877Y-289413D01*
X562440Y-287080D01*
Y-285038D01*
X562877Y-283289D01*
X563750Y-281246D01*
X565060Y-279497D01*
X566370Y-278330D01*
X568117Y-277455D01*
X569645D01*
X571392Y-278038D01*
X572702Y-279205D01*
G01X580595Y-294955D02*
Y-277455D01*
X590639Y-294955D01*
Y-277455D01*
G01X598314Y-294955D02*
Y-277455D01*
X602680D01*
X604427Y-278330D01*
X605737Y-279497D01*
X606829Y-281246D01*
X607702Y-283289D01*
X607920Y-286205D01*
X607702Y-289122D01*
X606829Y-291164D01*
X605737Y-292914D01*
X604427Y-294080D01*
X602680Y-294955D01*
X598314D01*
G01X670864Y-249955D02*
Y-232455D01*
X675230D01*
X676977Y-233330D01*
X678287Y-234497D01*
X679379Y-236246D01*
X680252Y-238289D01*
X680470Y-241205D01*
X680252Y-244122D01*
X679379Y-246164D01*
X678287Y-247914D01*
X676977Y-249080D01*
X675230Y-249955D01*
X670864D01*
G01X689892Y-242080D02*
X696879D01*
X696224Y-240038D01*
X695132Y-238872D01*
X693604Y-238289D01*
X692075Y-238580D01*
X690765Y-239455D01*
X689892Y-241497D01*
X689455Y-243247D01*
Y-244997D01*
X689892Y-246747D01*
X690984Y-248497D01*
X692294Y-249663D01*
X693822Y-249955D01*
X695350Y-249372D01*
X696879Y-247622D01*
G01X707392Y-247914D02*
X708484Y-249080D01*
X710012Y-249955D01*
X711322D01*
X712632Y-249372D01*
X713505Y-248497D01*
X713942Y-247331D01*
X713724Y-245580D01*
X712850Y-244705D01*
X708920Y-242955D01*
X708047Y-240913D01*
X708484Y-239455D01*
X709357Y-238580D01*
X710667Y-238289D01*
X711977Y-238580D01*
X713287Y-239455D01*
G01X728167Y-238289D02*
Y-249955D01*
G01Y-233622D02*
X727730Y-233330D01*
Y-232747D01*
X728167Y-232455D01*
X728604Y-232747D01*
Y-233330D01*
X728167Y-233622D01*
G01X742610Y-254330D02*
X744139Y-255497D01*
X745885Y-255788D01*
X747413Y-255497D01*
X748724Y-254039D01*
X749597Y-251997D01*
Y-238289D01*
G01Y-240622D02*
X748724Y-239455D01*
X747413Y-238580D01*
X745885Y-238289D01*
X744139Y-238872D01*
X743047Y-240038D01*
X742173Y-242080D01*
X741737Y-244122D01*
X741955Y-245872D01*
X742829Y-247914D01*
X744139Y-249372D01*
X745885Y-249955D01*
X747195Y-249663D01*
X748724Y-248497D01*
X749597Y-247331D01*
G01X759455Y-249955D02*
Y-238289D01*
G01Y-241205D02*
X760329Y-239747D01*
X761639Y-238580D01*
X763385Y-238289D01*
X764913Y-238580D01*
X766224Y-239747D01*
X766879Y-241788D01*
Y-249955D01*
G01X777392Y-242080D02*
X784379D01*
X783724Y-240038D01*
X782632Y-238872D01*
X781104Y-238289D01*
X779575Y-238580D01*
X778265Y-239455D01*
X777392Y-241497D01*
X776955Y-243247D01*
Y-244997D01*
X777392Y-246747D01*
X778484Y-248497D01*
X779794Y-249663D01*
X781322Y-249955D01*
X782850Y-249372D01*
X784379Y-247622D01*
G01X795110Y-249955D02*
Y-238289D01*
G01Y-240622D02*
X796202Y-239455D01*
X797294Y-238580D01*
X798822Y-238289D01*
X799913Y-238580D01*
X801224Y-239455D01*
G01X660367Y-277455D02*
X663423Y-294955D01*
X666917Y-277455D01*
X670410Y-294955D01*
X673467Y-277455D01*
G01X680050Y-294955D02*
Y-277455D01*
X685290D01*
X687037Y-278330D01*
X688347Y-280372D01*
X688784Y-282705D01*
X688347Y-285038D01*
X687255Y-286788D01*
X685290Y-287664D01*
X680050D01*
G01X697332Y-294955D02*
Y-277455D01*
G01X706502D02*
Y-294955D01*
G01Y-286205D02*
X697332D01*
G01X716579Y-289122D02*
X722255D01*
G01X732769Y-294955D02*
Y-277455D01*
X741065D01*
G01X738009Y-285913D02*
X732769D01*
G01X750050Y-277455D02*
Y-294955D01*
X758784D01*
G01X771917D02*
X770170Y-294663D01*
X768642Y-293497D01*
X767332Y-291747D01*
X766458Y-289705D01*
X766022Y-287372D01*
Y-285038D01*
X766458Y-282705D01*
X767332Y-280663D01*
X768642Y-278914D01*
X770170Y-277747D01*
X771917Y-277455D01*
X773663Y-277747D01*
X775192Y-278914D01*
X776502Y-280663D01*
X777376Y-282705D01*
X777812Y-285038D01*
Y-287372D01*
X777376Y-289705D01*
X776502Y-291747D01*
X775192Y-293497D01*
X773663Y-294663D01*
X771917Y-294955D01*
G01X785050D02*
Y-277455D01*
X790509D01*
X792255Y-278330D01*
X793347Y-279497D01*
X793784Y-281830D01*
X793347Y-284164D01*
X792037Y-285622D01*
X790509Y-286497D01*
X785050D01*
G01X790509D02*
X793784Y-294955D01*
G01X801458D02*
X806917Y-277455D01*
X812376Y-294955D01*
G01X810410Y-288830D02*
X803423D01*
G01X841867Y-294955D02*
Y-277455D01*
X839247Y-280955D01*
G01Y-294955D02*
X844487D01*
G01X859367D02*
Y-277455D01*
X856747Y-280955D01*
G01Y-294955D02*
X861987D01*
G01X872937Y-295538D02*
X880797Y-277455D01*
G01X894367Y-294955D02*
Y-277455D01*
X891747Y-280955D01*
G01Y-294955D02*
X896987D01*
G01X907719Y-287664D02*
X909247Y-285622D01*
X910557Y-284455D01*
X912304Y-283872D01*
X913832Y-284455D01*
X914924Y-285622D01*
X915797Y-287372D01*
X916015Y-289413D01*
X915797Y-291164D01*
X914924Y-292914D01*
X913613Y-294372D01*
X912085Y-294955D01*
X910339Y-294372D01*
X908810Y-292622D01*
X907937Y-289997D01*
X907719Y-287080D01*
X908155Y-283289D01*
X908810Y-281246D01*
X909902Y-279205D01*
X911430Y-277747D01*
X912959Y-277455D01*
X914487Y-278038D01*
X915579Y-279497D01*
G01X925437Y-295538D02*
X933297Y-277455D01*
G01X942719Y-280372D02*
X944029Y-278622D01*
X945557Y-277747D01*
X947304Y-277455D01*
X949487Y-278038D01*
X951015Y-279497D01*
X951452Y-281246D01*
X951234Y-282997D01*
X950360Y-284455D01*
X945994Y-287372D01*
X944029Y-289413D01*
X942719Y-292331D01*
X942282Y-294955D01*
X951452D01*
G01X964367Y-277455D02*
X962620Y-278038D01*
X961310Y-279497D01*
X960437Y-281246D01*
X959782Y-283580D01*
X959564Y-286205D01*
X959782Y-288830D01*
X960437Y-291164D01*
X961310Y-292914D01*
X962620Y-294372D01*
X964367Y-294955D01*
X966113Y-294372D01*
X967424Y-292914D01*
X968297Y-291164D01*
X968952Y-288830D01*
X969170Y-286205D01*
X968952Y-283580D01*
X968297Y-281246D01*
X967424Y-279497D01*
X966113Y-278038D01*
X964367Y-277455D01*
G01X981867Y-294955D02*
Y-277455D01*
X979247Y-280955D01*
G01Y-294955D02*
X984487D01*
G01X995219Y-287664D02*
X996747Y-285622D01*
X998057Y-284455D01*
X999804Y-283872D01*
X1001332Y-284455D01*
X1002424Y-285622D01*
X1003297Y-287372D01*
X1003515Y-289413D01*
X1003297Y-291164D01*
X1002424Y-292914D01*
X1001113Y-294372D01*
X999585Y-294955D01*
X997839Y-294372D01*
X996310Y-292622D01*
X995437Y-289997D01*
X995219Y-287080D01*
X995655Y-283289D01*
X996310Y-281246D01*
X997402Y-279205D01*
X998930Y-277747D01*
X1000459Y-277455D01*
X1001987Y-278038D01*
X1003079Y-279497D01*
G01X889564Y-249955D02*
Y-232455D01*
X893930D01*
X895677Y-233330D01*
X896987Y-234497D01*
X898079Y-236246D01*
X898952Y-238289D01*
X899170Y-241205D01*
X898952Y-244122D01*
X898079Y-246164D01*
X896987Y-247914D01*
X895677Y-249080D01*
X893930Y-249955D01*
X889564D01*
G01X915797D02*
Y-238289D01*
G01Y-240330D02*
X914924Y-239164D01*
X913613Y-238580D01*
X912085Y-238289D01*
X910557Y-238872D01*
X909247Y-240038D01*
X908373Y-241788D01*
X907937Y-244122D01*
X908373Y-246455D01*
X909247Y-248205D01*
X910557Y-249372D01*
X912085Y-249955D01*
X913613Y-249663D01*
X914924Y-248789D01*
X915797Y-247622D01*
G01X929367Y-232455D02*
Y-249955D01*
G01X926310Y-238289D02*
X932424D01*
G01X943592Y-242080D02*
X950579D01*
X949924Y-240038D01*
X948832Y-238872D01*
X947304Y-238289D01*
X945775Y-238580D01*
X944465Y-239455D01*
X943592Y-241497D01*
X943155Y-243247D01*
Y-244997D01*
X943592Y-246747D01*
X944684Y-248497D01*
X945994Y-249663D01*
X947522Y-249955D01*
X949050Y-249372D01*
X950579Y-247622D01*
G54D29*
G01X-106883Y-224955D02*
Y-304955D01*
G01Y-260455D02*
X1019417D01*
G01X-106883Y-304955D02*
X1019417D01*
G01X-110883Y-208955D02*
G02I-12000J0D01*
G01X-116033D02*
G02I-6850J0D01*
G01X-122883Y-224955D02*
Y-192955D01*
G01X-106883Y-208955D02*
X-138883D01*
G01X-106883Y-224955D02*
X1019417D01*
G01X231917D02*
Y-304955D01*
G01X369417Y-224955D02*
Y-304955D01*
G01X484417Y-224955D02*
Y-304955D01*
G01X651917Y-224955D02*
Y-304955D01*
G01X821917Y-224955D02*
Y-304955D01*
G01X1019417Y-224955D02*
Y-304955D01*
G01X1047417Y-208955D02*
G02I-12000J0D01*
G01X1042267D02*
G02I-6850J0D01*
G01X1035417Y-224955D02*
Y-192955D01*
G01X1051417Y-208955D02*
X1019417D01*
M02*
